G04 ================== begin FILE IDENTIFICATION RECORD ==================*
G04 Layout Name:  9048_F0T_Management_Board_D_brd_V04_1213_1625.brd*
G04 Film Name:    smb*
G04 File Format:  Gerber RS274X*
G04 File Origin:  Cadence Allegro 17.2-S081*
G04 Origin Date:  Tue Dec 13 16:31:10 2022*
G04 *
G04 Layer:  DRAWING FORMAT/TITLE_BLOCK_A*
G04 Layer:  DRAWING FORMAT/TITLE_BLOCK*
G04 Layer:  VIA CLASS/SOLDERMASK_BOTTOM*
G04 Layer:  PIN/SOLDERMASK_BOTTOM*
G04 Layer:  PACKAGE GEOMETRY/SOLDERMASK_BOTTOM*
G04 Layer:  MANUFACTURING/PHOTOPLOT_OUTLINE*
G04 Layer:  DRAWING FORMAT/TITLE_DATA_SMB*
G04 Layer:  BOARD GEOMETRY/SOLDERMASK_BOTTOM*
G04 *
G04 Offset:    (0.00 0.00)*
G04 Mirror:    No*
G04 Mode:      Positive*
G04 Rotation:  0*
G04 FullContactRelief:  No*
G04 UndefLineWidth:     6.00*
G04 ================== end FILE IDENTIFICATION RECORD ====================*
%FSLAX25Y25*MOIN*%
%IR0*IPPOS*OFA0.00000B0.00000*MIA0B0*SFA1.00000B1.00000*%
%ADD69R,.119X.04*%
%ADD17C,.03*%
%ADD36C,.022*%
%ADD65C,.032*%
%ADD74C,.024*%
%ADD80C,.061*%
%ADD42C,.052*%
%ADD23C,.065*%
%ADD11C,.056*%
%ADD63C,.048*%
%ADD10C,.085*%
%ADD33C,.068*%
%ADD30R,.052X.052*%
%AMMACRO82*
4,1,8,.08,.0445,
-.08,.0445,
-.08,-.0445,
-.0216,-.0445,
-.0216,-.0165,
.0216,-.0165,
.0216,-.0445,
.08,-.0445,
.08,.0445,
0.0*
%
%ADD82MACRO82*%
%ADD64C,.087*%
%ADD84C,.0395*%
%ADD24R,.065X.065*%
%ADD66R,.048X.048*%
%ADD85C,.0785*%
%AMMACRO53*
4,1,28,.00426,.01259,
.003485,.013262,
.002602,.013784,
.001641,.014146,
.000633,.014335,
-.000393,.014346,
-.001405,.014178,
-.002373,.013838,
-.003267,.013334,
-.004061,.012683,
-.00411,.01264,
-.00942,.00733,
-.00775,.00566,
-.01513,-.00172,
-.00172,-.01513,
.00566,-.00775,
.00733,-.00942,
.01264,-.00411,
.013297,-.003321,
.01381,-.002433,
.014162,-.001469,
.01434,-.000458,
.014341,.000568,
.014163,.001578,
.013812,.002543,
.0133,.003431,
.01264,.004218,
.01259,.00426,
.00426,.01259,
0.0*
%
%ADD53MACRO53*%
%AMMACRO47*
4,1,8,.0034,.0082,
-.0034,.0082,
-.0082,.0034,
-.0082,-.00341,
-.00341,-.0082,
.0034,-.0082,
.0082,-.0034,
.0082,.0034,
.0034,.0082,
0.0*
%
%ADD47MACRO47*%
%AMMACRO28*
4,1,28,-.00589,.01192,
-.006913,.011842,
-.007907,.011587,
-.008842,.011163,
-.009688,.010584,
-.010422,.009866,
-.011019,.009032,
-.011463,.008107,
-.011739,.007119,
-.01184,.006097,
-.01184,.00603,
-.01184,-.00148,
-.00948,-.00148,
-.00948,-.01191,
.00948,-.01191,
.00948,-.00148,
.01184,-.00148,
.01184,.00603,
.011751,.007052,
.011486,.008044,
.011053,.008974,
.010465,.009815,
.00974,.010541,
.0089,.01113,
.00797,.011564,
.006979,.01183,
.005957,.01192,
.00589,.01192,
-.00589,.01192,
0.0*
%
%ADD28MACRO28*%
%AMMACRO50*
4,1,8,.0082,-.0034,
.0082,.0034,
.0034,.0082,
-.00341,.0082,
-.0082,.00341,
-.0082,-.0034,
-.0034,-.0082,
.0034,-.0082,
.0082,-.0034,
0.0*
%
%ADD50MACRO50*%
%AMMACRO20*
4,1,28,.01192,.00589,
.011842,.006913,
.011587,.007907,
.011163,.008842,
.010584,.009688,
.009866,.010422,
.009032,.011019,
.008107,.011463,
.007119,.011739,
.006097,.01184,
.00603,.01184,
-.00148,.01184,
-.00148,.00948,
-.01191,.00948,
-.01191,-.00948,
-.00148,-.00948,
-.00148,-.01184,
.00603,-.01184,
.007052,-.011751,
.008044,-.011486,
.008974,-.011053,
.009815,-.010465,
.010541,-.00974,
.01113,-.0089,
.011564,-.00797,
.01183,-.006979,
.01192,-.005957,
.01192,-.00589,
.01192,.00589,
0.0*
%
%ADD20MACRO20*%
%AMMACRO51*
4,1,28,-.00425,-.01259,
-.003472,-.013259,
-.002588,-.01378,
-.001628,-.01414,
-.000619,-.014328,
.000407,-.014338,
.001419,-.01417,
.002387,-.013828,
.00328,-.013323,
.004072,-.012671,
.00412,-.01263,
.00943,-.00732,
.00776,-.00565,
.01513,.00173,
.00173,.01513,
-.00565,.00776,
-.00732,.00943,
-.01263,.00412,
-.013288,.003332,
-.013802,.002444,
-.014154,.00148,
-.014333,.00047,
-.014334,-.000556,
-.014157,-.001567,
-.013807,-.002531,
-.013295,-.003421,
-.012636,-.004207,
-.01259,-.00425,
-.00425,-.01259,
0.0*
%
%ADD51MACRO51*%
%AMMACRO27*
4,1,28,.0059,-.01191,
.006923,-.01183,
.007916,-.011573,
.00885,-.011148,
.009696,-.010567,
.010428,-.009849,
.011024,-.009013,
.011466,-.008088,
.011741,-.007099,
.01184,-.006078,
.01184,-.00602,
.01184,.00149,
.00948,.00149,
.00948,.01192,
-.00948,.01192,
-.00948,.00149,
-.01184,.00149,
-.01184,-.00602,
-.011751,-.007042,
-.011486,-.008033,
-.011053,-.008964,
-.010465,-.009805,
-.00974,-.010531,
-.0089,-.01112,
-.007971,-.011554,
-.00698,-.01182,
-.005958,-.01191,
-.0059,-.01191,
.0059,-.01191,
0.0*
%
%ADD27MACRO27*%
%AMMACRO14*
4,1,28,-.01191,-.0059,
-.01183,-.006923,
-.011573,-.007916,
-.011148,-.00885,
-.010567,-.009696,
-.009849,-.010428,
-.009013,-.011024,
-.008088,-.011466,
-.007099,-.011741,
-.006078,-.01184,
-.00602,-.01184,
.00149,-.01184,
.00149,-.00948,
.01192,-.00948,
.01192,.00948,
.00149,.00948,
.00149,.01184,
-.00602,.01184,
-.007042,.011751,
-.008033,.011486,
-.008964,.011053,
-.009805,.010465,
-.010531,.00974,
-.01112,.0089,
-.011554,.007971,
-.01182,.00698,
-.01191,.005958,
-.01191,.0059,
-.01191,-.0059,
0.0*
%
%ADD14MACRO14*%
%ADD70R,.03X.015*%
%ADD68R,.015X.03*%
%ADD73R,.04X.036*%
%ADD61R,.02X.028*%
%ADD21R,.028X.021*%
%ADD83R,.016X.024*%
%ADD78R,.017X.05*%
%ADD77R,.074X.021*%
%ADD75R,.036X.04*%
%ADD60R,.032X.044*%
%ADD58R,.036X.032*%
%ADD56R,.052X.043*%
%AMMACRO39*
21,1,.032,.036,0.0,0.0,45.*%
%ADD39MACRO39*%
%ADD31R,.021X.028*%
%ADD67R,.052X.044*%
%ADD52R,.032X.036*%
%ADD76C,.241*%
%ADD44R,.05X.038*%
%ADD79R,.054X.044*%
%ADD72R,.036X.026*%
%ADD29R,.03X.058*%
%ADD13C,.242*%
%ADD12C,.26*%
%ADD71R,.063X.018*%
%ADD59C,.135*%
%ADD22R,.044X.054*%
%ADD54R,.044X.029*%
%ADD48O,.256X.319*%
%ADD32R,.018X.063*%
%ADD19C,.145*%
%ADD18C,.118*%
%ADD62R,.028X.028*%
%ADD55R,.075X.044*%
%ADD40R,.019X.072*%
%ADD57R,.018X.048*%
%ADD49C,.319*%
%AMMACRO81*
4,1,8,-.08,-.0445,
.08,-.0445,
.08,.0445,
.0216,.0445,
.0216,.0165,
-.0216,.0165,
-.0216,.0445,
-.08,.0445,
-.08,-.0445,
0.0*
%
%ADD81MACRO81*%
%ADD43R,.058X.048*%
%ADD41R,.019X.088*%
%AMMACRO46*
4,1,8,-.0034,-.0082,
.0034,-.0082,
.0082,-.0034,
.0082,.00341,
.00341,.0082,
-.0034,.0082,
-.0082,.0034,
-.0082,-.0034,
-.0034,-.0082,
0.0*
%
%ADD46MACRO46*%
%AMMACRO45*
4,1,8,-.0082,.0034,
-.0082,-.0034,
-.0034,-.0082,
.00341,-.0082,
.0082,-.00341,
.0082,.0034,
.0034,.0082,
-.0034,.0082,
-.0082,.0034,
0.0*
%
%ADD45MACRO45*%
%AMMACRO38*
4,1,28,-.01259,.00426,
-.013262,.003485,
-.013784,.002602,
-.014146,.001641,
-.014335,.000633,
-.014346,-.000393,
-.014178,-.001405,
-.013838,-.002373,
-.013334,-.003267,
-.012683,-.004061,
-.01264,-.00411,
-.00733,-.00942,
-.00566,-.00775,
.00172,-.01513,
.01513,-.00172,
.00775,.00566,
.00942,.00733,
.00411,.01264,
.003321,.013297,
.002433,.01381,
.001469,.014162,
.000458,.01434,
-.000568,.014341,
-.001578,.014163,
-.002543,.013812,
-.003431,.0133,
-.004218,.01264,
-.00426,.01259,
-.01259,.00426,
0.0*
%
%ADD38MACRO38*%
%AMMACRO35*
4,1,28,-.00426,-.01259,
-.003485,-.013262,
-.002602,-.013784,
-.001641,-.014146,
-.000633,-.014335,
.000393,-.014346,
.001405,-.014178,
.002373,-.013838,
.003267,-.013334,
.004061,-.012683,
.00411,-.01264,
.00942,-.00733,
.00775,-.00566,
.01513,.00172,
.00172,.01513,
-.00566,.00775,
-.00733,.00942,
-.01264,.00411,
-.013297,.003321,
-.01381,.002433,
-.014162,.001469,
-.01434,.000458,
-.014341,-.000568,
-.014163,-.001578,
-.013812,-.002543,
-.0133,-.003431,
-.01264,-.004218,
-.01259,-.00426,
-.00426,-.01259,
0.0*
%
%ADD35MACRO35*%
%AMMACRO26*
4,1,28,-.01192,-.00589,
-.011842,-.006913,
-.011587,-.007907,
-.011163,-.008842,
-.010584,-.009688,
-.009866,-.010422,
-.009032,-.011019,
-.008107,-.011463,
-.007119,-.011739,
-.006097,-.01184,
-.00603,-.01184,
.00148,-.01184,
.00148,-.00948,
.01191,-.00948,
.01191,.00948,
.00148,.00948,
.00148,.01184,
-.00603,.01184,
-.007052,.011751,
-.008044,.011486,
-.008974,.011053,
-.009815,.010465,
-.010541,.00974,
-.01113,.0089,
-.011564,.00797,
-.01183,.006979,
-.01192,.005957,
-.01192,.00589,
-.01192,-.00589,
0.0*
%
%ADD26MACRO26*%
%AMMACRO16*
4,1,28,.00589,-.01192,
.006913,-.011842,
.007907,-.011587,
.008842,-.011163,
.009688,-.010584,
.010422,-.009866,
.011019,-.009032,
.011463,-.008107,
.011739,-.007119,
.01184,-.006097,
.01184,-.00603,
.01184,.00148,
.00948,.00148,
.00948,.01191,
-.00948,.01191,
-.00948,.00148,
-.01184,.00148,
-.01184,-.00603,
-.011751,-.007052,
-.011486,-.008044,
-.011053,-.008974,
-.010465,-.009815,
-.00974,-.010541,
-.0089,-.01113,
-.00797,-.011564,
-.006979,-.01183,
-.005957,-.01192,
-.00589,-.01192,
.00589,-.01192,
0.0*
%
%ADD16MACRO16*%
%AMMACRO37*
4,1,28,.01259,-.00425,
.013259,-.003472,
.01378,-.002588,
.01414,-.001628,
.014328,-.000619,
.014338,.000407,
.01417,.001419,
.013828,.002387,
.013323,.00328,
.012671,.004072,
.01263,.00412,
.00732,.00943,
.00565,.00776,
-.00173,.01513,
-.01513,.00173,
-.00776,-.00565,
-.00943,-.00732,
-.00412,-.01263,
-.003332,-.013288,
-.002444,-.013802,
-.00148,-.014154,
-.00047,-.014333,
.000556,-.014334,
.001567,-.014157,
.002531,-.013807,
.003421,-.013295,
.004207,-.012636,
.00425,-.01259,
.01259,-.00425,
0.0*
%
%ADD37MACRO37*%
%AMMACRO34*
4,1,28,.00425,.01259,
.003472,.013259,
.002588,.01378,
.001628,.01414,
.000619,.014328,
-.000407,.014338,
-.001419,.01417,
-.002387,.013828,
-.00328,.013323,
-.004072,.012671,
-.00412,.01263,
-.00943,.00732,
-.00776,.00565,
-.01513,-.00173,
-.00173,-.01513,
.00565,-.00776,
.00732,-.00943,
.01263,-.00412,
.013288,-.003332,
.013802,-.002444,
.014154,-.00148,
.014333,-.00047,
.014334,.000556,
.014157,.001567,
.013807,.002531,
.013295,.003421,
.012636,.004207,
.01259,.00425,
.00425,.01259,
0.0*
%
%ADD34MACRO34*%
%AMMACRO25*
4,1,28,.01191,.0059,
.01183,.006923,
.011573,.007916,
.011148,.00885,
.010567,.009696,
.009849,.010428,
.009013,.011024,
.008088,.011466,
.007099,.011741,
.006078,.01184,
.00602,.01184,
-.00149,.01184,
-.00149,.00948,
-.01192,.00948,
-.01192,-.00948,
-.00149,-.00948,
-.00149,-.01184,
.00602,-.01184,
.007042,-.011751,
.008033,-.011486,
.008964,-.011053,
.009805,-.010465,
.010531,-.00974,
.01112,-.0089,
.011554,-.007971,
.01182,-.00698,
.01191,-.005958,
.01191,-.0059,
.01191,.0059,
0.0*
%
%ADD25MACRO25*%
%AMMACRO15*
4,1,28,-.0059,.01191,
-.006923,.01183,
-.007916,.011573,
-.00885,.011148,
-.009696,.010567,
-.010428,.009849,
-.011024,.009013,
-.011466,.008088,
-.011741,.007099,
-.01184,.006078,
-.01184,.00602,
-.01184,-.00149,
-.00948,-.00149,
-.00948,-.01192,
.00948,-.01192,
.00948,-.00149,
.01184,-.00149,
.01184,.00602,
.011751,.007042,
.011486,.008033,
.011053,.008964,
.010465,.009805,
.00974,.010531,
.0089,.01112,
.007971,.011554,
.00698,.01182,
.005958,.01191,
.0059,.01191,
-.0059,.01191,
0.0*
%
%ADD15MACRO15*%
%ADD86C,.02*%
%ADD87C,.006*%
G75*
%LPD*%
G75*
G36*
G01X36759Y14328D02*
G03I-5900J0D01*
G37*
G36*
G01X37400Y443500D02*
G03I-5900J0D01*
G37*
G36*
G01X55177Y474015D02*
X52224Y471063D01*
Y461978D01*
X124508D01*
Y471063D01*
X121555Y474015D01*
X55177D01*
G37*
G36*
G01X143300Y323800D02*
G03I-5900J0D01*
G37*
G36*
G01X138287Y474015D02*
X135335Y471063D01*
Y461978D01*
X174547D01*
Y471063D01*
X171595Y474015D01*
X138287D01*
G37*
G36*
G01X184783D02*
X181831Y471063D01*
Y461978D01*
X254075D01*
Y471063D01*
X251122Y474015D01*
X184783D01*
G37*
G36*
G01X211800Y99500D02*
G03I-5900J0D01*
G37*
G36*
G01X276000Y198000D02*
G03I-5900J0D01*
G37*
G36*
G01X265886Y474015D02*
X262933Y471063D01*
Y461978D01*
X302126D01*
Y471063D01*
X299173Y474015D01*
X265886D01*
G37*
G36*
G01X302900Y270500D02*
G03I-5900J0D01*
G37*
G54D10*
X-56709Y43008D03*
X-61709Y56192D03*
X-51709D03*
X-61100Y250316D03*
X-56100Y263500D03*
X-61000Y382816D03*
X-56000Y396000D03*
X-51100Y250316D03*
X-51000Y382816D03*
X-30000Y43000D03*
X-35000Y56184D03*
X-25000D03*
X-25100Y250316D03*
X-35100D03*
X-30100Y263500D03*
X-36000Y418816D03*
X-26000D03*
X-31000Y432000D03*
G54D20*
X20083Y105500D03*
X19783Y116200D03*
X48383Y106200D03*
X49983Y376000D03*
Y384000D03*
Y388000D03*
Y380000D03*
X71983Y76500D03*
X69123Y335220D03*
X99983Y360000D03*
Y364000D03*
X116383Y109300D03*
X109008Y341649D03*
X109083Y337700D03*
X117583Y366600D03*
X117502Y362623D03*
X121083Y376800D03*
X135383Y84300D03*
X137083Y195600D03*
X127283Y234800D03*
Y238300D03*
X133983Y277000D03*
X130483Y361500D03*
X152943Y141056D03*
X138683Y250700D03*
X148733Y397500D03*
Y408000D03*
X167704Y157290D03*
X166833Y161150D03*
X166704Y181735D03*
X156503Y175720D03*
X166704Y185952D03*
Y190725D03*
X158691Y189082D03*
Y192582D03*
X160583Y228732D03*
X158208Y232300D03*
X157574Y242629D03*
X166515Y238479D03*
X171913Y212033D03*
X169583Y228400D03*
X172483Y267000D03*
X170417Y281848D03*
X187864Y194343D03*
X189869Y295096D03*
X188183Y300300D03*
X184983Y422800D03*
X212239Y178269D03*
X204471Y172304D03*
X210170Y194450D03*
X210313Y203530D03*
X199281Y217208D03*
X201714Y286781D03*
X209716Y278739D03*
X201983Y300400D03*
X222964Y172340D03*
Y176346D03*
X223260Y181892D03*
X224695Y193882D03*
X226073Y200555D03*
X225827Y210143D03*
X225693Y204555D03*
X218504Y216030D03*
X216739Y286782D03*
Y282756D03*
X225349Y275773D03*
X233983Y71000D03*
X239483Y109760D03*
X241890Y182782D03*
X235937Y194151D03*
X231578Y188938D03*
X240315Y205261D03*
X232691Y207040D03*
X236376Y283911D03*
X229376Y285912D03*
X233336Y275841D03*
Y279853D03*
X229462Y289941D03*
X235283Y306900D03*
X245083Y71900D03*
X256579Y158751D03*
X242942Y194151D03*
X256059Y203097D03*
X253310Y280778D03*
X253283Y359100D03*
Y355200D03*
X271483Y53000D03*
Y57000D03*
X271493Y117366D03*
X281285Y117391D03*
X283613Y175635D03*
X281147Y209511D03*
Y213530D03*
X288527Y165802D03*
X290920Y187914D03*
X293197Y393332D03*
X315883Y122000D03*
X306483Y131290D03*
X304565Y181885D03*
Y185885D03*
X316517Y188372D03*
X314788Y216137D03*
X311483Y373000D03*
X305733Y393352D03*
Y397382D03*
X328913Y159411D03*
X320892Y161378D03*
Y165378D03*
Y157378D03*
X328913Y179411D03*
Y183411D03*
Y187411D03*
Y191411D03*
X321913Y183411D03*
X337398Y104676D03*
Y112708D03*
Y108692D03*
X337308Y186961D03*
G54D11*
X17716Y18465D03*
X45276D03*
X264173Y20040D03*
X291733D03*
X309055Y18465D03*
X336615D03*
G54D12*
X22047Y46417D03*
X333466D03*
G54D21*
X27660Y106641D03*
Y111759D03*
Y109200D03*
X35140Y106641D03*
Y109200D03*
Y111759D03*
G54D30*
X63898Y24764D03*
X90472D03*
X117047D03*
X211142D03*
X237717D03*
G54D40*
X58839Y465590D03*
X61201D03*
X65925D03*
X73012D03*
X68287D03*
X75374D03*
X80098D03*
X87185D03*
X82461D03*
X89547D03*
X94272D03*
X101358D03*
X108445D03*
X96634D03*
X103721D03*
X115532D03*
X110807D03*
X117894D03*
X144311D03*
X151398D03*
X146673D03*
X158484D03*
X165571D03*
X153760D03*
X160846D03*
X167933D03*
X188445D03*
X190807D03*
X195532D03*
X197894D03*
X202618D03*
X204980D03*
X209705D03*
X212067D03*
X216791D03*
X219154D03*
X223878D03*
X226240D03*
X228602D03*
X230965D03*
X233327D03*
X235689D03*
X271890D03*
X274252D03*
X295512D03*
G54D22*
X25000Y240500D03*
X32000D03*
X166077Y327640D03*
X162077Y336440D03*
X170077D03*
G54D13*
X24016Y89331D03*
X330315D03*
G54D31*
X53441Y91260D03*
X56000D03*
X58559D03*
Y98740D03*
X53441D03*
G54D41*
X56476Y466378D03*
X63563D03*
X70650D03*
X77736D03*
X84823D03*
X91909D03*
X98996D03*
X106083D03*
X113169D03*
X120256D03*
X139587D03*
X141949D03*
X149035D03*
X156122D03*
X163209D03*
X170295D03*
X186083D03*
X193169D03*
X200256D03*
X207343D03*
X214429D03*
X221516D03*
X238051D03*
X240413D03*
X242776D03*
X245138D03*
X247500D03*
X249862D03*
X267165D03*
X269528D03*
X276614D03*
X278976D03*
X281339D03*
X283701D03*
X286063D03*
X288425D03*
X290787D03*
X293150D03*
X297874D03*
G54D32*
X61661Y247701D03*
Y265299D03*
X64220Y247701D03*
X66780D03*
X69339D03*
Y265299D03*
X66780D03*
X64220D03*
G54D14*
X17116Y105500D03*
X16816Y116200D03*
X45416Y106200D03*
X47016Y376000D03*
Y384000D03*
Y388000D03*
Y380000D03*
X69016Y76500D03*
X66156Y335220D03*
X106041Y341649D03*
X106116Y337700D03*
X97016Y360000D03*
Y364000D03*
X113416Y109300D03*
X114616Y366600D03*
X114535Y362623D03*
X118116Y376800D03*
X132416Y84300D03*
X134116Y195600D03*
X124316Y234800D03*
Y238300D03*
X135716Y250700D03*
X131016Y277000D03*
X127516Y361500D03*
X149976Y141056D03*
X145766Y397500D03*
Y408000D03*
X164737Y157290D03*
X163866Y161150D03*
X163737Y181735D03*
X153536Y175720D03*
X163737Y185952D03*
Y190725D03*
X155724Y189082D03*
Y192582D03*
X157616Y228732D03*
X155241Y232300D03*
X154607Y242629D03*
X163548Y238479D03*
X166616Y228400D03*
X167450Y281848D03*
X168946Y212033D03*
X169516Y267000D03*
X182016Y422800D03*
X184897Y194343D03*
X196314Y217208D03*
X186902Y295096D03*
X185216Y300300D03*
X209272Y178269D03*
X201504Y172304D03*
X207203Y194450D03*
X207346Y203530D03*
X198747Y286781D03*
X206749Y278739D03*
X199016Y300400D03*
X219997Y172340D03*
Y176346D03*
X220293Y181892D03*
X221728Y193882D03*
X223106Y200555D03*
X222860Y210143D03*
X222726Y204555D03*
X215537Y216030D03*
X213772Y286782D03*
Y282756D03*
X222382Y275773D03*
X226409Y285912D03*
X226495Y289941D03*
X231016Y71000D03*
X242116Y71900D03*
X236516Y109760D03*
X238923Y182782D03*
X232970Y194151D03*
X239975D03*
X228611Y188938D03*
X237348Y205261D03*
X229724Y207040D03*
X233409Y283911D03*
X230369Y275841D03*
Y279853D03*
X232316Y306900D03*
X253612Y158751D03*
X253092Y203097D03*
X250343Y280778D03*
X250316Y359100D03*
Y355200D03*
X268516Y53000D03*
Y57000D03*
X268526Y117366D03*
X278318Y117391D03*
X285560Y165802D03*
X280646Y175635D03*
X278180Y209511D03*
Y213530D03*
X301598Y181885D03*
Y185885D03*
X287953Y187914D03*
X290230Y393332D03*
X312916Y122000D03*
X303516Y131290D03*
X313550Y188372D03*
X311821Y216137D03*
X308516Y373000D03*
X302766Y393352D03*
Y397382D03*
X325946Y159411D03*
X317925Y161378D03*
Y165378D03*
Y157378D03*
X325946Y179411D03*
Y183411D03*
Y187411D03*
Y191411D03*
X318946Y183411D03*
X334431Y104676D03*
Y112708D03*
Y108692D03*
X334341Y186961D03*
G54D50*
X90761Y368528D03*
X87611D03*
X92360Y382626D03*
X100539Y378300D03*
X97389D03*
X95510Y382626D03*
G54D23*
X23819Y339154D03*
Y349154D03*
Y359154D03*
Y369154D03*
Y379154D03*
Y389154D03*
Y399154D03*
X65709Y52244D03*
X75709Y42244D03*
Y52244D03*
X95709Y42244D03*
X85709D03*
X95709Y52244D03*
X85709D03*
G54D15*
X16800Y112384D03*
X21000Y322484D03*
X48000Y97484D03*
X40400Y420284D03*
X44400D03*
X55500Y72984D03*
X59500D03*
X55500Y81984D03*
X60000Y106484D03*
X61216Y232784D03*
X64500Y71984D03*
X68500D03*
X65216Y232784D03*
X74300Y277584D03*
X66000Y287984D03*
X71900Y309984D03*
X64100Y330984D03*
X76500D03*
X78500Y402984D03*
X74500D03*
X70500D03*
X82500Y71984D03*
X90500Y74984D03*
X88700Y330984D03*
X82500Y402984D03*
X92809Y420814D03*
X88800Y420784D03*
X98500Y72484D03*
X105600Y333684D03*
X101200Y374784D03*
X103800Y384484D03*
X94500Y402984D03*
X102500D03*
X96814Y420814D03*
X115600Y121009D03*
X111600D03*
X120250Y164534D03*
X117400Y419784D03*
X132400Y91384D03*
X129500Y119484D03*
X125500Y120984D03*
X124500Y164534D03*
X127546Y231206D03*
X130000Y402484D03*
X138000Y420234D03*
X128500Y420984D03*
X139500Y143984D03*
X152450Y209278D03*
X148050Y364684D03*
X146000Y420234D03*
X150000D03*
X142000D03*
X155500Y27984D03*
X166733Y122810D03*
X156525Y153186D03*
X156467Y209278D03*
X159164Y223673D03*
X159930Y239094D03*
X160973Y252495D03*
X156963D03*
X165013D03*
X160765Y260447D03*
X156695Y260459D03*
X164801Y260445D03*
X157600Y420284D03*
X153800D03*
X179400Y17684D03*
X169500Y27484D03*
X169000Y77984D03*
X170738Y122810D03*
X178761D03*
X174741D03*
X181541Y213115D03*
X177500Y245584D03*
X173600D03*
X173992Y260315D03*
X169934Y260317D03*
X176700Y349884D03*
X181400Y365784D03*
X177500D03*
X178500Y382684D03*
X182500D03*
X194830Y83044D03*
X185470Y96434D03*
X188980Y96444D03*
X187431Y122971D03*
X191434D03*
X195500Y122984D03*
X196000Y114984D03*
X191000Y137984D03*
X195000D03*
X196332Y146900D03*
X197463Y171972D03*
X187596Y190319D03*
X193724Y189164D03*
X194567Y197581D03*
X188500Y206784D03*
X194485Y238522D03*
X198000Y264134D03*
X193800Y348384D03*
X204000Y122984D03*
X207800D03*
X199500D03*
X211370Y123004D03*
X200000Y114984D03*
X199000Y137884D03*
X207000D03*
X207486Y188953D03*
X199465Y188984D03*
X203476Y188953D03*
X206672Y212368D03*
X210333Y218539D03*
X212100Y250284D03*
X208500Y261884D03*
X201792Y274702D03*
X209811D03*
X205810D03*
X210600Y308184D03*
X227500Y96484D03*
X227370Y123010D03*
X215294D03*
X223338D03*
X219313D03*
X227061Y176337D03*
X216855Y189899D03*
X215958Y200905D03*
X213245Y241884D03*
X218800Y253544D03*
X219900Y261384D03*
X225363Y261584D03*
X223400Y268484D03*
X217120Y293778D03*
X223920Y376544D03*
X215800Y422784D03*
X233500Y96984D03*
X239590Y123010D03*
X231415D03*
X241826Y137853D03*
X231111Y176312D03*
X241200Y168384D03*
X237954Y178766D03*
X228712Y196554D03*
X239064Y212246D03*
X231021Y215721D03*
X235064D03*
X235100Y254784D03*
X239100Y253684D03*
X231250Y250434D03*
X238413Y245023D03*
X242430Y245523D03*
X242690Y260759D03*
X229265Y261907D03*
X248000Y96984D03*
X256333Y123010D03*
X243609Y123049D03*
X248087Y113123D03*
X252111D03*
X247500Y124984D03*
X252374Y137853D03*
X244500Y209484D03*
Y216484D03*
X250465Y245637D03*
X254466Y245727D03*
X246430Y245523D03*
X260346Y122510D03*
X265866Y147234D03*
X261800Y245684D03*
Y286784D03*
X265400Y420534D03*
X261400D03*
X286452Y148223D03*
X282440D03*
X282907Y186942D03*
X282240Y197743D03*
X283579Y241008D03*
X285911Y275406D03*
X281889D03*
Y285136D03*
X285911D03*
X301936Y141406D03*
X290487Y148223D03*
X301507Y192944D03*
X294162Y369036D03*
X310500Y118484D03*
X314000Y133234D03*
X310200D03*
X313936Y141406D03*
X309936D03*
X305936D03*
X305507Y192944D03*
X317116Y202434D03*
X318000Y133234D03*
X317936Y141406D03*
X321602Y190404D03*
G54D60*
X126610Y377576D03*
X134090D03*
Y387024D03*
X130350D03*
X126610D03*
X256510Y368576D03*
Y378024D03*
X260250Y368576D03*
X263990D03*
Y378024D03*
X260250D03*
G54D51*
X107936Y390478D03*
X103450Y391450D03*
G54D24*
X23819Y409154D03*
X65709Y42244D03*
G54D33*
X65945Y297776D03*
G54D42*
X73898Y24764D03*
X100472D03*
X127047D03*
X221142D03*
X247717D03*
G54D25*
X48384Y102300D03*
X58484Y86000D03*
X50014Y220480D03*
X49984Y344000D03*
Y348000D03*
Y360000D03*
X59684Y376300D03*
X59984Y367700D03*
X49984Y368000D03*
X59684Y372600D03*
X49984Y372000D03*
X73184Y287100D03*
X78784Y296700D03*
X80984Y76000D03*
X105945Y78566D03*
X115384Y249900D03*
X117484Y358500D03*
X119484Y397000D03*
X129284Y249700D03*
X130084Y283000D03*
X125484Y277000D03*
X130484Y357500D03*
Y353500D03*
X142784Y78700D03*
X148378Y152844D03*
X151184Y182110D03*
X150568Y192600D03*
X146264Y378760D03*
Y382760D03*
X148734Y392000D03*
Y401750D03*
X158384Y119200D03*
X163684Y147000D03*
X166484Y165500D03*
X167709Y153400D03*
X166484Y169500D03*
X166684Y173200D03*
X166705Y176885D03*
X158689Y181573D03*
X158692Y185582D03*
X163468Y206305D03*
X162468Y202305D03*
X156661Y326128D03*
Y330164D03*
X174274Y300900D03*
X196384Y209700D03*
Y206200D03*
X196484Y213200D03*
X192277Y217208D03*
X184861Y238444D03*
X190174Y267000D03*
X189889Y283155D03*
X186384Y279200D03*
X189889Y287221D03*
X189857Y291172D03*
X197534Y410250D03*
X211476Y172289D03*
X203277Y177969D03*
X200337Y181969D03*
X202170Y194415D03*
X203474Y203510D03*
X206305Y216270D03*
X201898Y237255D03*
X201715Y278743D03*
X209717Y286782D03*
X201715Y282773D03*
X203734Y342250D03*
Y338750D03*
X203234Y345750D03*
Y356250D03*
Y352750D03*
Y349250D03*
Y359750D03*
Y363250D03*
Y367250D03*
Y370750D03*
X217696Y193921D03*
X225518Y216136D03*
X222484Y245800D03*
X225350Y279783D03*
X219936Y372129D03*
X238097Y171773D03*
X233935Y180866D03*
X231333Y184938D03*
X229463Y293960D03*
X236884Y374100D03*
X242364Y378220D03*
X255984Y51500D03*
X250027Y194772D03*
X253311Y276756D03*
X253284Y351200D03*
Y363100D03*
X264484Y49000D03*
X271484D03*
X264484Y53000D03*
X271596Y104703D03*
Y108226D03*
X270284Y384100D03*
X277066Y121400D03*
X298484Y97600D03*
X298884Y116300D03*
X296184Y131700D03*
X295984Y126500D03*
X301335Y205854D03*
X293198Y397365D03*
X308664Y200789D03*
X314284Y260300D03*
X314984Y369000D03*
X329372Y104676D03*
Y108692D03*
Y112707D03*
X321018Y153377D03*
X328330Y150140D03*
X328914Y155411D03*
Y167411D03*
Y163411D03*
Y175411D03*
X320893Y173378D03*
Y177378D03*
X328914Y171411D03*
X320893Y169378D03*
X324745Y203664D03*
Y207664D03*
X337309Y154911D03*
Y158911D03*
Y162911D03*
Y166911D03*
X337237Y170911D03*
X337309Y182926D03*
Y178911D03*
X337237Y174911D03*
X337309Y190961D03*
X332544Y210288D03*
Y202288D03*
Y206288D03*
X333976Y386635D03*
Y390701D03*
G54D34*
X62550Y349850D03*
G54D16*
X16800Y109417D03*
X21000Y319517D03*
X48000Y94517D03*
X40400Y417317D03*
X44400D03*
X55500Y70017D03*
X59500D03*
X55500Y79017D03*
X60000Y103517D03*
X61216Y229817D03*
X64500Y69017D03*
X68500D03*
X65216Y229817D03*
X66000Y285017D03*
X74300Y274617D03*
X71900Y307017D03*
X64100Y328017D03*
X76500D03*
X78500Y400017D03*
X74500D03*
X70500D03*
X82500Y69017D03*
X90500Y72017D03*
X88700Y328017D03*
X82500Y400017D03*
X92809Y417847D03*
X88800Y417817D03*
X98500Y69517D03*
X105600Y330717D03*
X101200Y371817D03*
X103800Y381517D03*
X94500Y400017D03*
X102500D03*
X96814Y417847D03*
X115600Y118042D03*
X111600D03*
X120250Y161567D03*
X117400Y416817D03*
X132400Y88417D03*
X129500Y116517D03*
X125500Y118017D03*
X124500Y161567D03*
X127546Y228239D03*
X130000Y399517D03*
X138000Y417267D03*
X128500Y418017D03*
X139500Y141017D03*
X152450Y206311D03*
X148050Y361717D03*
X146000Y417267D03*
X150000D03*
X142000D03*
X155500Y25017D03*
X166733Y119843D03*
X156525Y150219D03*
X156467Y206311D03*
X159164Y220706D03*
X159930Y236127D03*
X160765Y257480D03*
X156695Y257492D03*
X164801Y257478D03*
X160973Y249528D03*
X156963D03*
X165013D03*
X157600Y417317D03*
X153800D03*
X179400Y14717D03*
X169500Y24517D03*
X169000Y75017D03*
X170738Y119843D03*
X178761D03*
X174741D03*
X181541Y210148D03*
X177500Y242617D03*
X173600D03*
X173992Y257348D03*
X169934Y257350D03*
X176700Y346917D03*
X181400Y362817D03*
X177500D03*
X178500Y379717D03*
X182500D03*
X185470Y93467D03*
X188980Y93477D03*
X194830Y80077D03*
X187431Y120004D03*
X191434D03*
X195500Y120017D03*
X196000Y112017D03*
X191000Y135017D03*
X195000D03*
X196332Y143933D03*
X197463Y169005D03*
X187596Y187352D03*
X193724Y186197D03*
X194567Y194614D03*
X188500Y203817D03*
X194485Y235555D03*
X198000Y261167D03*
X193800Y345417D03*
X204000Y120017D03*
X207800D03*
X199500D03*
X211370Y120037D03*
X200000Y112017D03*
X199000Y134917D03*
X207000D03*
X207486Y185986D03*
X199465Y186017D03*
X203476Y185986D03*
X206672Y209401D03*
X210333Y215572D03*
X212100Y247317D03*
X201792Y271735D03*
X208500Y258917D03*
X209811Y271735D03*
X205810D03*
X210600Y305217D03*
X227500Y93517D03*
X227370Y120043D03*
X215294D03*
X223338D03*
X219313D03*
X227061Y173370D03*
X215958Y197938D03*
X216855Y186932D03*
X213245Y238917D03*
X218800Y250577D03*
X219900Y258417D03*
X225363Y258617D03*
X223400Y265517D03*
X217120Y290811D03*
X223920Y373577D03*
X215800Y419817D03*
X233500Y94017D03*
X239590Y120043D03*
X231415D03*
X241826Y134886D03*
X241200Y165417D03*
X231111Y173345D03*
X237954Y175799D03*
X228712Y193587D03*
X231021Y212754D03*
X235064D03*
X239064Y209279D03*
X238413Y242056D03*
X242430Y242556D03*
X235100Y251817D03*
X239100Y250717D03*
X231250Y247467D03*
X242690Y257792D03*
X229265Y258940D03*
X248000Y94017D03*
X247500Y122017D03*
X256333Y120043D03*
X243609Y120082D03*
X248087Y110156D03*
X252111D03*
X252374Y134886D03*
X244500Y206517D03*
Y213517D03*
X250465Y242670D03*
X254466Y242760D03*
X246430Y242556D03*
X260346Y119543D03*
X265866Y144267D03*
X261800Y242717D03*
Y283817D03*
X265400Y417567D03*
X261400D03*
X286452Y145256D03*
X282440D03*
X282907Y183975D03*
X282240Y194776D03*
X283579Y238041D03*
X285911Y272439D03*
X281889D03*
Y282169D03*
X285911D03*
X301936Y138439D03*
X290487Y145256D03*
X301507Y189977D03*
X294162Y366069D03*
X310500Y115517D03*
X313936Y138439D03*
X309936D03*
X305936D03*
X314000Y130267D03*
X310200D03*
X305507Y189977D03*
X317116Y199467D03*
X317936Y138439D03*
X318000Y130267D03*
X321602Y187437D03*
G54D43*
X79000Y90760D03*
X70500D03*
X79000Y98240D03*
X70500D03*
X86500Y90760D03*
Y98240D03*
X95700Y90760D03*
Y98240D03*
G54D52*
X107500Y404400D03*
Y398600D03*
X137500Y123100D03*
Y128900D03*
X129928Y144932D03*
Y139132D03*
X129795Y150150D03*
Y155950D03*
X216066Y211321D03*
Y205521D03*
X266570Y131569D03*
Y137369D03*
X272311Y148785D03*
Y142985D03*
X272057Y254604D03*
Y260404D03*
X270200Y372000D03*
Y366200D03*
X277731Y148785D03*
Y142985D03*
X281000Y160100D03*
Y165900D03*
X283478Y225651D03*
Y231451D03*
X278153Y254604D03*
X283990Y254605D03*
X278153Y260404D03*
X283990Y260405D03*
X300157Y217162D03*
Y222962D03*
X294528Y221264D03*
Y227064D03*
X289102Y225598D03*
Y231398D03*
X326000Y126100D03*
Y131900D03*
X330500Y228300D03*
X322000Y235400D03*
Y229600D03*
X330500Y234100D03*
G54D61*
X150900Y12657D03*
X171400D03*
X230500Y79457D03*
X245000D03*
G54D70*
X154842Y365153D03*
Y363185D03*
X171378Y365153D03*
Y363185D03*
G54D26*
X45417Y102300D03*
X47047Y220480D03*
X47017Y344000D03*
Y348000D03*
Y360000D03*
Y368000D03*
Y372000D03*
X55517Y86000D03*
X56717Y376300D03*
X57017Y367700D03*
X56717Y372600D03*
X78017Y76000D03*
X70217Y287100D03*
X75817Y296700D03*
X102978Y78566D03*
X112417Y249900D03*
X122517Y277000D03*
X114517Y358500D03*
X116517Y397000D03*
X126317Y249700D03*
X127117Y283000D03*
X127517Y357500D03*
Y353500D03*
X139817Y78700D03*
X145411Y152844D03*
X148217Y182110D03*
X147601Y192600D03*
X143297Y378760D03*
Y382760D03*
X145767Y392000D03*
Y401750D03*
X155417Y119200D03*
X160717Y147000D03*
X163517Y165500D03*
X164742Y153400D03*
X163517Y169500D03*
X163717Y173200D03*
X163738Y176885D03*
X155722Y181573D03*
X155725Y185582D03*
X160501Y206305D03*
X159501Y202305D03*
X153694Y326128D03*
Y330164D03*
X181894Y238444D03*
X171307Y300900D03*
X197370Y181969D03*
X193417Y209700D03*
Y206200D03*
X193517Y213200D03*
X189310Y217208D03*
X187207Y267000D03*
X186922Y283155D03*
X183417Y279200D03*
X186922Y287221D03*
X186890Y291172D03*
X194567Y410250D03*
X208509Y172289D03*
X200310Y177969D03*
X199203Y194415D03*
X200507Y203510D03*
X203338Y216270D03*
X198931Y237255D03*
X198748Y278743D03*
X206750Y286782D03*
X198748Y282773D03*
X200767Y342250D03*
Y338750D03*
X200267Y345750D03*
Y356250D03*
Y352750D03*
Y349250D03*
Y359750D03*
Y363250D03*
Y367250D03*
Y370750D03*
X214729Y193921D03*
X222551Y216136D03*
X219517Y245800D03*
X222383Y279783D03*
X226496Y293960D03*
X216969Y372129D03*
X235130Y171773D03*
X230968Y180866D03*
X228366Y184938D03*
X233917Y374100D03*
X239397Y378220D03*
X253017Y51500D03*
X247060Y194772D03*
X250344Y276756D03*
X250317Y351200D03*
Y363100D03*
X261517Y49000D03*
X268517D03*
X261517Y53000D03*
X268629Y104703D03*
Y108226D03*
X267317Y384100D03*
X274099Y121400D03*
X295517Y97600D03*
X295917Y116300D03*
X293217Y131700D03*
X293017Y126500D03*
X298368Y205854D03*
X290231Y397365D03*
X305697Y200789D03*
X311317Y260300D03*
X312017Y369000D03*
X326405Y104676D03*
Y108692D03*
Y112707D03*
X318051Y153377D03*
X325363Y150140D03*
X325947Y155411D03*
Y167411D03*
Y163411D03*
Y175411D03*
X317926Y173378D03*
Y177378D03*
X325947Y171411D03*
X317926Y169378D03*
X321778Y203664D03*
X329577Y210288D03*
X321778Y207664D03*
X329577Y202288D03*
Y206288D03*
X331009Y386635D03*
Y390701D03*
X334342Y154911D03*
Y158911D03*
Y162911D03*
Y166911D03*
X334270Y170911D03*
X334342Y182926D03*
Y178911D03*
X334270Y174911D03*
X334342Y190961D03*
G54D35*
X60451Y347751D03*
G54D62*
X147947Y12657D03*
Y19743D03*
X168447Y12657D03*
X153853D03*
X168447Y19743D03*
X153853D03*
X174353Y12657D03*
Y19743D03*
X227547Y86543D03*
Y79457D03*
X242047Y86543D03*
Y79457D03*
X233453Y86543D03*
Y79457D03*
X247953Y86543D03*
Y79457D03*
G54D71*
X161296Y391448D03*
Y404244D03*
Y401685D03*
Y399125D03*
Y396566D03*
Y394007D03*
Y409362D03*
Y406803D03*
X181179Y316084D03*
Y313524D03*
Y310965D03*
Y308406D03*
Y305847D03*
Y323761D03*
Y321202D03*
Y318643D03*
X184296Y391448D03*
Y394007D03*
Y396566D03*
Y399125D03*
Y401685D03*
Y404244D03*
Y406803D03*
Y409362D03*
X204179Y305847D03*
Y308406D03*
Y310965D03*
Y313524D03*
Y316084D03*
Y318643D03*
Y321202D03*
Y323761D03*
X215420Y344273D03*
Y341714D03*
Y339155D03*
Y359628D03*
Y357069D03*
Y354510D03*
Y351950D03*
Y349391D03*
Y346832D03*
Y367305D03*
Y364746D03*
Y362187D03*
X238420Y339155D03*
Y341714D03*
Y344273D03*
Y346832D03*
Y349391D03*
Y351950D03*
Y354510D03*
Y357069D03*
Y359628D03*
Y362187D03*
Y364746D03*
Y367305D03*
G54D44*
X77761Y301897D03*
Y308393D03*
X86029Y301897D03*
Y308393D03*
G54D53*
X105549Y393549D03*
X110035Y392577D03*
G54D80*
X372604Y-455313D03*
Y-430313D03*
X372664Y-223791D03*
Y-198791D03*
X372576Y-177041D03*
Y-152041D03*
X372664Y4481D03*
Y29481D03*
X372604Y51231D03*
Y76231D03*
X372664Y373753D03*
Y398753D03*
X393692Y-481375D03*
X382604Y-455313D03*
X393692Y-456375D03*
X382604Y-430313D03*
X382664Y-223791D03*
Y-198791D03*
X382576Y-177041D03*
Y-152041D03*
X393780Y-128853D03*
Y-103853D03*
X393750Y-82222D03*
Y-57222D03*
X382664Y4481D03*
Y29481D03*
X382604Y51231D03*
Y76231D03*
X393750Y200538D03*
Y225538D03*
Y247050D03*
Y272050D03*
X382664Y373753D03*
X393750Y398810D03*
X382664Y398753D03*
X393750Y423810D03*
X403692Y-481375D03*
Y-456375D03*
X403780Y-128853D03*
Y-103853D03*
X403750Y-82222D03*
D03*
Y-57222D03*
D03*
Y200538D03*
D03*
Y225538D03*
D03*
Y247050D03*
D03*
Y272050D03*
D03*
Y398810D03*
D03*
Y423810D03*
D03*
X413750Y-82222D03*
Y-57222D03*
Y200538D03*
Y225538D03*
Y247050D03*
Y272050D03*
Y398810D03*
Y423810D03*
G54D17*
X18800Y122100D03*
X19000Y129500D03*
X18500Y163300D03*
X7809Y168397D03*
X21400Y178100D03*
X7809Y183397D03*
Y198397D03*
X19100Y187420D03*
X7809Y213397D03*
Y228397D03*
X18000Y234500D03*
X7809Y243397D03*
Y258397D03*
X17065Y255712D03*
X7809Y273397D03*
Y288397D03*
X8200Y302800D03*
X22000Y111400D03*
X36500Y129500D03*
X29000D03*
X24000Y138500D03*
X26000Y209500D03*
X27500Y202000D03*
X28000Y223500D03*
X26000Y216500D03*
X29900Y231400D03*
X32100Y252800D03*
X24705Y258767D03*
X22237Y304626D03*
X30638Y304602D03*
Y311957D03*
X33000Y318700D03*
X35300Y323900D03*
X29100Y327000D03*
X36200Y368400D03*
X31500Y428500D03*
X40175Y29713D03*
X40000Y104200D03*
X45000Y122500D03*
X37500Y116500D03*
X40940Y112559D03*
X51500Y114000D03*
X45000Y129500D03*
X49400Y161800D03*
X47294Y184491D03*
X48035Y191535D03*
X39408Y195990D03*
X48940Y204871D03*
X40600Y203000D03*
X39900Y211000D03*
X39567Y243133D03*
X47800Y240843D03*
X51500Y258200D03*
X37485Y258807D03*
X41100Y248900D03*
X47440Y304225D03*
X39039Y301299D03*
Y311933D03*
X50950Y318050D03*
X44481Y328760D03*
X38560Y329739D03*
X37020Y385600D03*
X46100Y412700D03*
X38000Y428800D03*
X45100Y435800D03*
X45300Y426400D03*
X59549Y63000D03*
X59945Y117795D03*
X60800Y137000D03*
X52410Y186900D03*
X59700Y196200D03*
X65380Y213120D03*
X52948Y200700D03*
X58000Y217700D03*
X55100Y225500D03*
X64500Y240400D03*
X59500Y240500D03*
X61200Y276400D03*
Y282600D03*
X55500Y315000D03*
X65400Y311900D03*
X60600Y318000D03*
X52800Y322400D03*
X59820Y341030D03*
X66070Y339780D03*
X65400Y344200D03*
X54500Y341390D03*
X54530Y348200D03*
X54500Y355000D03*
X59600Y363100D03*
X65000Y377500D03*
X54800Y381800D03*
X54600Y388000D03*
X61924Y383476D03*
X55500Y395600D03*
X58000Y412600D03*
X63715Y412385D03*
X62455Y426870D03*
X78781Y64635D03*
X74757Y83745D03*
X76580Y121904D03*
X66900Y125300D03*
X76500Y135000D03*
X70450Y138610D03*
X71124Y178565D03*
X66700Y220520D03*
X71100Y229741D03*
X74583Y217314D03*
X76200Y247400D03*
X77437Y262760D03*
X72300Y282500D03*
X77500Y316100D03*
X73301Y319575D03*
X81000Y321900D03*
X78900Y336600D03*
X71700Y340600D03*
X74500Y335700D03*
X81355Y390300D03*
X79000Y395500D03*
X73976Y408665D03*
X69139Y413452D03*
X74782Y413800D03*
X73971Y429200D03*
X91358Y83745D03*
X88500Y128000D03*
X81500Y176515D03*
X87500Y237300D03*
X92300Y282100D03*
X94812Y301312D03*
X93000Y315000D03*
X88700Y318300D03*
X92698Y323224D03*
X84800Y344100D03*
X92900Y342800D03*
X88700Y337123D03*
X83900Y385700D03*
X94200Y391000D03*
X96030Y409400D03*
X84320Y430510D03*
X94710Y433260D03*
X89500Y432000D03*
X84000Y425500D03*
X105722Y59722D03*
X111000Y77000D03*
X104500Y73500D03*
X110950Y82050D03*
X111075Y104600D03*
X98720Y236980D03*
X103580Y237400D03*
X106600Y253689D03*
X106574Y280028D03*
X99990Y307900D03*
X100500Y328547D03*
X98377Y341523D03*
X105900Y376900D03*
X98500Y394800D03*
X108701Y418300D03*
X108336Y411547D03*
X109048Y425853D03*
X106550Y431630D03*
X103461Y425875D03*
X125800Y47330D03*
X112800Y60400D03*
X112600Y52800D03*
X125800Y69000D03*
X113000Y88500D03*
X123325Y111000D03*
X120500Y115525D03*
X120300Y134800D03*
X118990Y128536D03*
X113590Y245170D03*
X112900Y239200D03*
X124559Y255500D03*
X115475Y254900D03*
X111600Y262730D03*
X113157Y270929D03*
X111600Y284000D03*
X122957Y300991D03*
X123100Y295974D03*
X124935Y324900D03*
X124300Y348800D03*
X114060Y340640D03*
X119370Y344050D03*
X122200Y356400D03*
X111950Y371200D03*
X122047Y372260D03*
X125650Y368650D03*
X122330Y364670D03*
X119200Y389700D03*
X117410Y381350D03*
X112800Y421600D03*
X116632Y411500D03*
X122498Y419675D03*
X112796Y412490D03*
X117900Y425980D03*
X140730Y72600D03*
X133000Y78900D03*
X126800Y132900D03*
X140500Y134500D03*
X132500Y167300D03*
X128900Y183700D03*
X135300Y175100D03*
X133433Y186400D03*
X138900Y219500D03*
X127200Y223700D03*
X134891Y225171D03*
X138608Y235001D03*
X133608D03*
X138000Y244600D03*
X137059Y255568D03*
X134788Y283000D03*
X136100Y334000D03*
X140950Y390050D03*
X127950Y395750D03*
X134400Y394600D03*
X129135Y410250D03*
X128866Y433066D03*
X135350Y433016D03*
X128500Y426070D03*
X140820Y433030D03*
X134805Y427395D03*
X143000Y17310D03*
X146200Y28075D03*
X151000Y24925D03*
X152801Y70349D03*
X152800Y75600D03*
X145100Y87400D03*
X147587Y119813D03*
X149800Y135100D03*
X144800Y141700D03*
X148429Y147682D03*
X144500Y169570D03*
X146882Y177501D03*
X148967Y173433D03*
X141694Y196204D03*
X145100Y208800D03*
X143742Y203395D03*
X152400Y226300D03*
X142702Y227817D03*
X149862Y243788D03*
X150430Y231000D03*
X145250Y256890D03*
X152300Y248200D03*
X147150Y273000D03*
X141890Y310570D03*
X153500Y373400D03*
X145703Y370700D03*
X150210Y369250D03*
X148490Y374259D03*
X153330Y391710D03*
X152500Y382600D03*
X150820Y387325D03*
X154110Y404090D03*
X154638Y396566D03*
X146000Y429900D03*
X141185Y426899D03*
X158732Y12625D03*
X158952Y20203D03*
X169500Y32000D03*
X165000Y24500D03*
X156710Y73420D03*
X168985Y71000D03*
X156286Y124903D03*
X166733Y128700D03*
X159328Y160847D03*
X164000Y197700D03*
X169000Y199000D03*
X157500Y214700D03*
X170600Y204300D03*
X170000Y223500D03*
X169520Y252810D03*
X160300Y281848D03*
X161635Y276500D03*
X160850Y301344D03*
X170800Y317600D03*
X159510Y312500D03*
X161154Y376704D03*
X156300Y376300D03*
X165501Y382800D03*
X158200Y381400D03*
X162100Y414000D03*
X156101Y425100D03*
X165500Y433100D03*
X184500Y15500D03*
X182108Y129094D03*
X174553Y128728D03*
X175400Y149000D03*
X175450Y143704D03*
X181752Y147052D03*
X171507Y162892D03*
X171600Y178000D03*
X171677Y172607D03*
X171443Y183557D03*
X176800Y194200D03*
X176144Y232863D03*
X179754Y250150D03*
X180458Y258825D03*
X174400Y251936D03*
X181863Y289871D03*
X175013Y281583D03*
X178900Y301100D03*
X172800Y354646D03*
X178682Y430173D03*
X184480Y429370D03*
X174830Y427848D03*
X172060Y433100D03*
X190500Y18000D03*
X193100Y69100D03*
X194600Y89900D03*
X194500Y106200D03*
X186891Y113991D03*
X187435Y129623D03*
X195983Y129294D03*
X187172Y143672D03*
X200400Y151600D03*
X193267Y278328D03*
X200396Y291531D03*
X194294Y300400D03*
X187180Y329590D03*
X187570Y337590D03*
X194200Y351930D03*
X189500Y368900D03*
X187400Y379400D03*
X187300Y384300D03*
X197660Y390870D03*
X195800Y396780D03*
X190370Y422490D03*
X199940Y423700D03*
X197600Y415400D03*
X194600Y419660D03*
X192470Y414850D03*
X188239Y417654D03*
X195300Y432327D03*
X204100Y67400D03*
X204504Y113507D03*
X211490Y143700D03*
X202247Y145400D03*
X211300Y151100D03*
X207610Y242910D03*
X210770Y313524D03*
X210930Y318643D03*
X202440Y333420D03*
X208320Y348291D03*
X208300Y338200D03*
X208315Y343235D03*
X208340Y353360D03*
X208350Y358370D03*
X208120Y363410D03*
X202240Y378980D03*
X208350Y369750D03*
X210550Y375290D03*
X208360Y384890D03*
X208565Y404501D03*
X205223Y422665D03*
X206150Y412821D03*
X223800Y50700D03*
X224000Y74275D03*
X226000Y68000D03*
X216400Y106400D03*
X226040Y101220D03*
X222100Y112100D03*
X229342Y129240D03*
X221278Y129294D03*
X228766Y142545D03*
X218631Y151131D03*
X221400Y142600D03*
X223007Y153967D03*
X217000Y233800D03*
X227820Y233900D03*
X230196Y267477D03*
X218400Y270400D03*
X226783Y298849D03*
X216384Y312216D03*
X228800Y312100D03*
X218500Y318800D03*
X219220Y307580D03*
X216250Y328130D03*
X228680Y376635D03*
X222575Y387625D03*
X227206Y400100D03*
X220134Y400780D03*
X240000Y67400D03*
X235630Y104990D03*
X231592Y110500D03*
X235880Y115000D03*
X242500Y129000D03*
X236623Y128797D03*
X239118Y145170D03*
X239624Y154064D03*
X232384Y148884D03*
X244850Y153350D03*
X238385Y232466D03*
X235070Y236989D03*
X239298Y268800D03*
X241277Y274649D03*
X234946Y271298D03*
X235108Y262780D03*
X241263Y282654D03*
X239693Y288930D03*
X234693D03*
X238900Y296950D03*
X245300Y361100D03*
X234815Y379895D03*
X243250Y385930D03*
X256000Y56000D03*
X259106Y66000D03*
X252900Y80400D03*
X254900Y92500D03*
X256500Y98500D03*
X257422Y129840D03*
X258500Y146400D03*
X247546Y142562D03*
X252586Y142376D03*
X248988Y157001D03*
X258500Y169000D03*
X259200Y163600D03*
X260000Y210900D03*
X259800Y222600D03*
X247700Y229400D03*
X259000Y237600D03*
X259500Y258800D03*
X250900Y250800D03*
X253100Y257800D03*
X258100Y295080D03*
X245900Y305000D03*
X246000Y333900D03*
X257046Y331377D03*
X254340Y346320D03*
X256320Y341490D03*
X256124Y336355D03*
X245400Y355800D03*
X245430Y367305D03*
X257095Y428796D03*
X267939Y41122D03*
X272505Y83545D03*
X267060Y124750D03*
X268256Y112794D03*
X272100Y137400D03*
X260733Y154500D03*
X267909Y185096D03*
X271209Y177524D03*
X264200Y172300D03*
X266346Y219380D03*
X264100Y235500D03*
X266647Y252636D03*
X261800Y250300D03*
X260500Y300500D03*
X262310Y311225D03*
X261300Y334100D03*
X274190Y408900D03*
X269700Y411379D03*
X271500Y418300D03*
X267100Y432900D03*
X263800Y430300D03*
X272999Y430500D03*
X262190Y425300D03*
X286000Y47000D03*
X290000Y82000D03*
X277505Y83545D03*
X282505D03*
X278394Y111035D03*
X278220Y101530D03*
X288116Y120306D03*
X280400Y126000D03*
X287796Y131542D03*
X288280Y126212D03*
X286000Y157000D03*
X287908Y170320D03*
X289254Y194839D03*
X286106Y210587D03*
X289000Y244900D03*
X288192Y237704D03*
X289701Y255679D03*
X278029Y249108D03*
X284357Y267027D03*
X287507Y301596D03*
X289939Y309060D03*
X289600Y322253D03*
X286372Y326768D03*
X283973Y382553D03*
X285472Y394583D03*
X278900Y421400D03*
X281300Y416200D03*
X277700Y412580D03*
X280765Y431556D03*
X297466Y51521D03*
X297575Y73738D03*
X290840Y96350D03*
X304000Y116500D03*
X291360Y116390D03*
X300500Y125000D03*
X296075Y122000D03*
X292200Y154900D03*
X300819Y154564D03*
X292572Y160025D03*
X295410Y172936D03*
X298714Y210477D03*
X292404Y201282D03*
X299667Y201334D03*
X292404Y213737D03*
X290700Y221600D03*
X303688Y237034D03*
X303918Y243252D03*
X299100Y286500D03*
X291000Y297700D03*
X298705Y369127D03*
X298152Y393332D03*
X292700Y403700D03*
X317000Y111500D03*
X315100Y116400D03*
X309394Y153989D03*
X311269Y159165D03*
X310598Y174488D03*
X305002Y172936D03*
X310866Y179672D03*
X311158Y194839D03*
Y210587D03*
X309521Y226397D03*
X305700Y216300D03*
X309521Y235352D03*
X319700Y248600D03*
X316276Y255376D03*
X312114Y288439D03*
X312272Y282107D03*
X307668Y285160D03*
X306200Y308800D03*
X307000Y367500D03*
X310431Y393352D03*
X308926Y401900D03*
X321800Y109000D03*
X320938Y122677D03*
X322530Y138950D03*
X331641Y141743D03*
X328798Y216364D03*
X323798D03*
X322700Y288600D03*
X330200D03*
X322700Y296100D03*
Y303600D03*
X330200D03*
Y296100D03*
X325900Y365643D03*
X326100Y375717D03*
X326200Y370681D03*
X326375Y380724D03*
X333300Y403400D03*
X321100Y410400D03*
X339101Y117328D03*
X337842Y128533D03*
X335400Y133400D03*
X343600Y133900D03*
X337700Y144300D03*
Y227900D03*
X347500Y350000D03*
X335475Y367500D03*
X347500Y388000D03*
X335500Y380000D03*
G54D45*
X70313Y354280D03*
X73463D03*
X70313Y357429D03*
X73463D03*
X70312Y351130D03*
X73462D03*
X76589Y370000D03*
X70312Y373177D03*
X73462D03*
X70312Y376327D03*
X73462D03*
X79739Y370000D03*
X98659Y351130D03*
X101809D03*
Y354280D03*
X104959D03*
X103425Y357500D03*
X106575D03*
X93711Y374528D03*
X96861D03*
X94425Y367500D03*
X97575D03*
X94425Y371000D03*
X97575D03*
G54D81*
X377604Y-443963D03*
X398692Y-470025D03*
X398750Y-70872D03*
X408750Y258400D03*
G54D18*
X30859Y14328D03*
X31500Y443500D03*
X137400Y323800D03*
X205900Y99500D03*
X270100Y198000D03*
X297000Y270500D03*
G54D54*
X116500Y78889D03*
Y83711D03*
G54D72*
X178355Y87450D03*
Y83710D03*
Y79970D03*
X187803D03*
Y87450D03*
G54D27*
X44500Y212516D03*
X40980Y371116D03*
X48500Y417516D03*
X59500Y79016D03*
X56100Y328016D03*
X60000D03*
X52200D03*
X50000Y353016D03*
X56500Y417516D03*
X52500D03*
X60500D03*
X72500Y69016D03*
X76500D03*
X69500Y236016D03*
X66000Y274516D03*
X70000D03*
X68000Y316516D03*
X72000Y328016D03*
X68100D03*
X75000Y387016D03*
X69000D03*
X86500Y69016D03*
X80600Y254916D03*
X86500Y400016D03*
X94500Y69516D03*
X104000Y361016D03*
X98500Y400016D03*
X112500Y126016D03*
X123500Y125016D03*
X119370Y348796D03*
X135500Y141016D03*
X126000Y399516D03*
X152000Y252816D03*
Y260016D03*
X163400Y12716D03*
X162657Y119842D03*
X166717Y134885D03*
X173000Y75016D03*
X181960Y93466D03*
X170737Y134885D03*
X182954D03*
X174740D03*
X178816D03*
X177300Y216816D03*
X181300Y242516D03*
X169700Y243316D03*
X172800Y346916D03*
X178000Y338841D03*
X178500Y379716D03*
X182500D03*
X182600Y414966D03*
X187000Y135016D03*
X193343Y178502D03*
X193550Y171692D03*
X184890Y242531D03*
X192501Y250273D03*
X188500Y250266D03*
X190693Y243069D03*
X194729D03*
X197790Y271734D03*
X187070Y259426D03*
X194100Y261196D03*
X187220Y346016D03*
X210800Y134885D03*
X202900Y135016D03*
X206912Y144205D03*
X211494Y187150D03*
X198990Y242028D03*
X202990D03*
X206238Y235265D03*
X200460Y250276D03*
X204000Y261116D03*
X221500Y64516D03*
X214500Y135016D03*
X218500D03*
X222500D03*
X226500D03*
X215498Y169217D03*
X216265Y179907D03*
X222190Y185945D03*
X217200Y238716D03*
X223269Y237916D03*
X227116Y249940D03*
X214100Y255716D03*
X223100Y249316D03*
X213833Y267608D03*
X217862Y275753D03*
X213813Y275762D03*
X222293Y283801D03*
X221154Y290810D03*
X241700Y94016D03*
X235510Y120042D03*
X234500Y135216D03*
X230500Y135016D03*
X238025Y186882D03*
X238337Y198169D03*
X232713Y198176D03*
X230520Y238916D03*
X253000Y72016D03*
X244082Y108264D03*
X256100Y110116D03*
X245836Y134885D03*
X252600Y126316D03*
X256700Y134885D03*
X257500Y274016D03*
X250300Y367816D03*
X243250Y392766D03*
X260200Y134886D03*
X261863Y144338D03*
X268897Y159446D03*
X263897D03*
X271470Y216445D03*
X281000Y76016D03*
X277000D03*
X285000D03*
X276000Y162516D03*
X278868Y183974D03*
X282192Y201791D03*
X286611Y216625D03*
X283383Y245668D03*
X301936Y146388D03*
X297357Y233233D03*
X305000Y121016D03*
X313936Y146388D03*
X309936D03*
X305936D03*
X316979Y192460D03*
X317111Y208525D03*
X317936Y146388D03*
G54D63*
X153237Y58583D03*
X165048Y52677D03*
X161111Y58583D03*
X168985D03*
X182764Y52677D03*
X172922D03*
X176859Y58583D03*
X184733D03*
G54D36*
X62458Y355873D03*
X58564Y354280D03*
X65607Y352724D03*
Y359023D03*
Y371584D03*
X75056Y346425D03*
X68757D03*
X81355D03*
X78206Y349574D03*
Y359023D03*
X68757Y362173D03*
X71906Y365322D03*
X87617Y352724D03*
X93916D03*
X100253Y346387D03*
X181495Y153449D03*
X175196Y156599D03*
X184645Y166047D03*
Y181795D03*
X181495Y172347D03*
X184645Y175496D03*
X178346D03*
X181495Y188095D03*
X175196Y200655D03*
X181495Y203805D03*
X175196Y206955D03*
X184645Y219553D03*
X178346Y229002D03*
X184645D03*
X197243Y159748D03*
X190944D03*
Y166047D03*
X200393Y162898D03*
X187794Y156599D03*
Y172347D03*
X194094Y222703D03*
X200393Y229002D03*
X187794Y225852D03*
X200393Y222703D03*
X209842Y159748D03*
X206692Y162898D03*
X209842Y166047D03*
X212991Y162898D03*
X203542Y159748D03*
Y225852D03*
X206692Y229002D03*
X212991D03*
X206692Y222703D03*
X225552Y166047D03*
X222402Y159748D03*
X228739Y222703D03*
X228702Y229002D03*
X225590Y225852D03*
X222440Y222703D03*
X222402Y229002D03*
X219290Y225852D03*
X231851Y166047D03*
X235001Y156599D03*
X244450Y200655D03*
X231889Y225890D03*
X250749Y169197D03*
X253898Y175496D03*
X250749Y184945D03*
X257048Y197506D03*
Y191244D03*
G54D37*
X60036Y389478D03*
G54D46*
X76664Y376425D03*
X76612Y363729D03*
Y366879D03*
X76664Y379575D03*
X70332Y379457D03*
Y382607D03*
X83864Y362325D03*
Y365475D03*
X79852Y363825D03*
Y366975D03*
X104958Y347981D03*
Y351131D03*
X98664Y382625D03*
Y385775D03*
G54D55*
X125100Y75091D03*
Y86509D03*
G54D19*
X27300Y68200D03*
X340639Y432809D03*
G54D73*
X177037Y418500D03*
X169163Y414760D03*
Y422240D03*
X237937Y390000D03*
X230063Y386260D03*
Y393740D03*
X253294Y394747D03*
X261168Y391007D03*
Y398487D03*
G54D28*
X44500Y215483D03*
X40980Y374083D03*
X48500Y420483D03*
X59500Y81983D03*
X56100Y330983D03*
X60000D03*
X52200D03*
X50000Y355983D03*
X56500Y420483D03*
X52500D03*
X60500D03*
X72500Y71983D03*
X76500D03*
X69500Y238983D03*
X66000Y277483D03*
X70000D03*
X68000Y319483D03*
X72000Y330983D03*
X68100D03*
X75000Y389983D03*
X69000D03*
X86500Y71983D03*
X80600Y257883D03*
X86500Y402983D03*
X94500Y72483D03*
X104000Y363983D03*
X98500Y402983D03*
X112500Y128983D03*
X123500Y127983D03*
X119370Y351763D03*
X135500Y143983D03*
X126000Y402483D03*
X152000Y255783D03*
Y262983D03*
X163400Y15683D03*
X162657Y122809D03*
X166717Y137852D03*
X173000Y77983D03*
X181960Y96433D03*
X170737Y137852D03*
X182954D03*
X174740D03*
X178816D03*
X177300Y219783D03*
X169700Y246283D03*
X181300Y245483D03*
X178000Y341808D03*
X172800Y349883D03*
X178500Y382683D03*
X182500D03*
X182600Y417933D03*
X187000Y137983D03*
X193343Y181469D03*
X193550Y174659D03*
X192501Y253240D03*
X188500Y253233D03*
X190693Y246036D03*
X194729D03*
X184890Y245498D03*
X187070Y262393D03*
X194100Y264163D03*
X197790Y274701D03*
X187220Y348983D03*
X210800Y137852D03*
X202900Y137983D03*
X206912Y147172D03*
X211494Y190117D03*
X206238Y238232D03*
X200460Y253243D03*
X198990Y244995D03*
X202990D03*
X204000Y264083D03*
X221500Y67483D03*
X214500Y137983D03*
X218500D03*
X222500D03*
X226500D03*
X215498Y172184D03*
X216265Y182874D03*
X222190Y188912D03*
X217200Y241683D03*
X223269Y240883D03*
X227116Y252907D03*
X223100Y252283D03*
X213833Y270575D03*
X214100Y258683D03*
X217862Y278720D03*
X213813Y278729D03*
X222293Y286768D03*
X221154Y293777D03*
X241700Y96983D03*
X235510Y123009D03*
X234500Y138183D03*
X230500Y137983D03*
X238025Y189849D03*
X238337Y201136D03*
X232713Y201143D03*
X230520Y241883D03*
X253000Y74983D03*
X256100Y113083D03*
X244082Y111231D03*
X245836Y137852D03*
X252600Y129283D03*
X256700Y137852D03*
X257500Y276983D03*
X250300Y370783D03*
X243250Y395733D03*
X260200Y137853D03*
X261863Y147305D03*
X268897Y162413D03*
X263897D03*
X271470Y219412D03*
X281000Y78983D03*
X277000D03*
X285000D03*
X276000Y165483D03*
X278868Y186941D03*
X282192Y204758D03*
X286611Y219592D03*
X283383Y248635D03*
X301936Y149355D03*
X297357Y236200D03*
X305000Y123983D03*
X313936Y149355D03*
X309936D03*
X305936D03*
X316979Y195427D03*
X317111Y211492D03*
X317936Y149355D03*
G54D64*
X144685Y297776D03*
G54D82*
X377664Y-210141D03*
X398780Y-115203D03*
X398750Y214188D03*
X408750Y412460D03*
G54D38*
X57937Y391577D03*
G54D29*
X48500Y396276D03*
Y405724D03*
G54D56*
X122156Y141343D03*
Y154257D03*
X113000Y141500D03*
Y154414D03*
G54D83*
X376620Y-440713D03*
X378588D03*
X378648Y-213391D03*
X376680D03*
X397708Y-466775D03*
X399676D03*
X399764Y-118453D03*
X397796D03*
X397766Y-67622D03*
X399734D03*
Y210938D03*
X397766D03*
X407766Y261650D03*
X409734D03*
Y409210D03*
X407766D03*
G54D47*
X73482Y382626D03*
Y379476D03*
X89210Y360579D03*
Y357429D03*
X83900Y359275D03*
Y356125D03*
X82911Y376327D03*
Y373177D03*
X86061Y376327D03*
Y373177D03*
X89210Y376327D03*
Y373177D03*
G54D74*
X189300Y148400D03*
X219600Y147000D03*
G54D65*
X151420Y432880D03*
X204056Y128935D03*
X261800Y107300D03*
X261700Y114700D03*
G54D57*
X122000Y269437D03*
X119441D03*
Y261563D03*
X122000D03*
X124559Y269437D03*
Y261563D03*
X137059Y269437D03*
X134500D03*
X131941D03*
Y261563D03*
X134500D03*
X137059D03*
G54D48*
X105315Y186571D03*
G54D39*
X59949Y398551D03*
X64051Y394449D03*
G54D75*
X227510Y57613D03*
X234990D03*
X231250Y65487D03*
X294157Y376023D03*
X297897Y383897D03*
X290417D03*
X308486Y378422D03*
X312226Y386296D03*
X304746D03*
G54D66*
X155205Y52677D03*
G54D84*
X441000Y-444000D03*
X451000D03*
Y-355000D03*
X441000D03*
Y-323400D03*
X451000D03*
Y-245000D03*
X441000D03*
X451000Y-215000D03*
X441000D03*
Y-136600D03*
X451000D03*
Y-107000D03*
X441000D03*
Y-18000D03*
X451000D03*
X441000Y12000D03*
X451000D03*
Y96000D03*
X441000D03*
Y126000D03*
X451000D03*
Y200000D03*
X441000D03*
X451000Y230000D03*
X441000D03*
Y304000D03*
X451000D03*
Y336000D03*
X441000D03*
Y420000D03*
X451000D03*
G54D49*
X105316Y213343D03*
G54D76*
X236220Y424016D03*
X301181D03*
G54D67*
X166895Y291162D03*
X175713Y287225D03*
Y295099D03*
G54D58*
X115100Y402000D03*
X120900D03*
X148400Y129000D03*
X142600D03*
X148748Y220947D03*
X154548D03*
X165824Y217706D03*
X164300Y233100D03*
X171624Y217706D03*
X170100Y233100D03*
X256510Y384400D03*
X271812Y154663D03*
X270100Y170500D03*
X272100Y224500D03*
X262310Y384400D03*
X277300Y137400D03*
X283100D03*
X277612Y154663D03*
X275900Y170500D03*
X277900Y224500D03*
X281914Y218630D03*
X276114D03*
X291488Y137870D03*
X297288D03*
X327200Y120250D03*
X323611Y196486D03*
X329411D03*
X333000Y120250D03*
G54D85*
X441000Y-454000D03*
X451000D03*
Y-345000D03*
X441000D03*
Y-333400D03*
X451000D03*
Y-235000D03*
X441000D03*
X451000Y-225000D03*
X441000D03*
Y-126600D03*
X451000D03*
Y-117000D03*
X441000D03*
Y-8000D03*
X451000D03*
X441000Y2000D03*
X451000D03*
Y106000D03*
X441000D03*
Y116000D03*
X451000D03*
Y210000D03*
X441000D03*
X451000Y220000D03*
X441000D03*
Y314000D03*
X451000D03*
Y326000D03*
X441000D03*
Y430000D03*
X451000D03*
G54D86*
G01X0Y7874D02*
G03X7874Y0I7874J0D01*
G01X0Y319882D02*
Y7874D01*
G01X984Y320866D02*
G03X0Y319882I0J-984D01*
G01X8858Y320866D02*
X984D01*
G01Y334646D02*
X8858D01*
G01X0Y335630D02*
G03X984Y334646I984J0D01*
G01X0Y442126D02*
Y335630D01*
G01X7874Y450000D02*
G03X0Y442126I0J-7874D01*
G01X7874Y0D02*
X346457D01*
G01X10827Y322835D02*
G02X8858Y320866I-1969J0D01*
G01X10827Y332677D02*
Y322835D01*
G01X8858Y334646D02*
G02X10827Y332677I0J-1969D01*
G01X17717Y450000D02*
X7874D01*
G01X19685Y451969D02*
G02X17717Y450000I-1969J0D01*
G01X19685Y469024D02*
Y451969D01*
G01X22567Y474016D02*
X19685Y469024D01*
G01X39429Y474016D02*
X22567D01*
G01X44350Y450000D02*
G02X42382Y451969I0J1969D01*
G01X50256Y450000D02*
X44350D01*
G01X42382Y451969D02*
Y471063D01*
G01D02*
X39429Y474016D01*
G01X52224Y451969D02*
G02X50256Y450000I-1969J0D01*
G01X52224Y471063D02*
Y451969D01*
G01X55177Y474016D02*
X52224Y471063D01*
G01X121555Y474016D02*
X55177D01*
G01X124508Y471063D02*
X121555Y474016D01*
G01X135335Y451870D02*
G02X124508I-5413J0D01*
G01D02*
Y471063D01*
G01X135335D02*
Y451870D01*
G01X138287Y474016D02*
X135335Y471063D01*
G01X171594Y474016D02*
X138287D01*
G01X174547Y450098D02*
Y471063D01*
G01X181831Y450098D02*
G02X174547I-3642J0D01*
G01X181831Y471063D02*
Y450098D01*
G01X174547Y471063D02*
X171594Y474016D01*
G01X184783D02*
X181831Y471063D01*
G01X251122Y474016D02*
X184783D01*
G01X262933Y450886D02*
G02X254075I-4429J0D01*
G01D02*
Y471063D01*
G01D02*
X251122Y474016D01*
G01X262933Y471063D02*
Y450886D01*
G01X265886Y474016D02*
X262933Y471063D01*
G01X299173Y474016D02*
X265886D01*
G01X304094Y450000D02*
G02X302126Y451969I1J1969D01*
G01D02*
Y471063D01*
G01D02*
X299173Y474016D01*
G01X310000Y450000D02*
X304094D01*
G01X311969Y451969D02*
G02X310000Y450000I-1969J0D01*
G01X311969Y471063D02*
Y451969D01*
G01X314921Y474016D02*
X311969Y471063D01*
G01X331764Y474016D02*
X314921D01*
G01X334646Y469024D02*
X331764Y474016D01*
G01X346457Y0D02*
G03X354331Y7874I0J7874D01*
G01X343504Y322835D02*
Y332677D01*
G01X345472Y320866D02*
G02X343504Y322835I0J1968D01*
G01X353346Y320866D02*
X345472D01*
G01Y334646D02*
X353346D01*
G01X343504Y332677D02*
G02X345472Y334646I1968J0D01*
G01X336614Y450000D02*
G02X334646Y451969I0J1969D01*
G01X346457Y450000D02*
X336614D01*
G01X354331Y442126D02*
G03X346457Y450000I-7874J0D01*
G01X334646Y451969D02*
Y469024D01*
G01X354331Y7874D02*
Y319882D01*
G01D02*
G03X353346Y320866I-984J0D01*
G01X354331Y335630D02*
Y442126D01*
G01X353346Y334646D02*
G03X354331Y335630I1J984D01*
G54D59*
X143118Y44803D03*
X194851D03*
G54D77*
X286549Y103090D03*
Y105649D03*
Y108209D03*
Y110768D03*
X309935Y103090D03*
Y105649D03*
Y108209D03*
Y110768D03*
G54D68*
X156220Y359838D03*
X158189D03*
X160157D03*
X162126D03*
X164094D03*
X166063D03*
Y368500D03*
X164094D03*
X162126D03*
X160157D03*
X158189D03*
X156220D03*
X168031Y359838D03*
X170000D03*
Y368500D03*
X168031D03*
G54D87*
G01X2010999Y-388000D02*
Y1475775D01*
X-407000D01*
Y-386798D01*
Y-755294D01*
Y-793716D01*
X-368578D01*
X1942346D01*
X2010999D01*
Y-725063D01*
Y-388000D01*
G01X-53307Y-609436D02*
Y-684436D01*
X446693D01*
Y-609436D01*
X-53307D01*
G01X-41307Y-674436D02*
Y-679436D01*
G01X-42764Y-674436D02*
X-39850D01*
G01X-34940Y-679436D02*
X-37474D01*
Y-674436D01*
X-34940D01*
G01X-35954Y-676853D02*
X-37474D01*
G01X-32374Y-674436D02*
Y-679436D01*
X-29840D01*
G01X-26007Y-679603D02*
X-26134Y-679519D01*
Y-679353D01*
X-26007Y-679269D01*
X-25880Y-679353D01*
Y-679519D01*
X-26007Y-679603D01*
G01Y-677353D02*
X-26134Y-677269D01*
Y-677103D01*
X-26007Y-677019D01*
X-25880Y-677103D01*
Y-677269D01*
X-26007Y-677353D01*
G01X-21224Y-681103D02*
X-21857Y-680269D01*
X-22174Y-679436D01*
Y-676103D01*
X-21857Y-675269D01*
X-21224Y-674436D01*
G01X-15807D02*
X-16314Y-674603D01*
X-16694Y-675019D01*
X-16947Y-675519D01*
X-17137Y-676186D01*
X-17200Y-676936D01*
X-17137Y-677686D01*
X-16947Y-678353D01*
X-16694Y-678853D01*
X-16314Y-679269D01*
X-15807Y-679436D01*
X-15300Y-679269D01*
X-14920Y-678853D01*
X-14667Y-678353D01*
X-14477Y-677686D01*
X-14414Y-676936D01*
X-14477Y-676186D01*
X-14667Y-675519D01*
X-14920Y-675019D01*
X-15300Y-674603D01*
X-15807Y-674436D01*
G01X-12100Y-678436D02*
X-11720Y-679019D01*
X-11214Y-679353D01*
X-10644Y-679436D01*
X-10137Y-679353D01*
X-9630Y-678936D01*
X-9314Y-678436D01*
X-9250Y-677936D01*
X-9377Y-677353D01*
X-9820Y-676936D01*
X-10264Y-676769D01*
X-10834D01*
G01X-10264D02*
X-9884Y-676519D01*
X-9567Y-676103D01*
X-9440Y-675603D01*
X-9567Y-675103D01*
X-9884Y-674686D01*
X-10454Y-674436D01*
X-11024Y-674519D01*
X-11594Y-674853D01*
G01X-5290Y-681103D02*
X-4657Y-680269D01*
X-4340Y-679436D01*
Y-676103D01*
X-4657Y-675269D01*
X-5290Y-674436D01*
G01X-1900Y-678436D02*
X-1520Y-679019D01*
X-1014Y-679353D01*
X-444Y-679436D01*
X63Y-679353D01*
X570Y-678936D01*
X886Y-678436D01*
X950Y-677936D01*
X823Y-677353D01*
X380Y-676936D01*
X-64Y-676769D01*
X-634D01*
G01X-64D02*
X316Y-676519D01*
X633Y-676103D01*
X760Y-675603D01*
X633Y-675103D01*
X316Y-674686D01*
X-254Y-674436D01*
X-824Y-674519D01*
X-1394Y-674853D01*
G01X3390Y-675269D02*
X3770Y-674769D01*
X4213Y-674519D01*
X4720Y-674436D01*
X5353Y-674603D01*
X5796Y-675019D01*
X5923Y-675519D01*
X5860Y-676019D01*
X5606Y-676436D01*
X4340Y-677269D01*
X3770Y-677853D01*
X3390Y-678686D01*
X3263Y-679436D01*
X5923D01*
G01X9566D02*
X9693Y-678353D01*
X9883Y-677436D01*
X10136Y-676603D01*
X10453Y-675686D01*
X10960Y-674436D01*
X8426D01*
G01X13970Y-677769D02*
X15616D01*
G01X18690Y-675269D02*
X19070Y-674769D01*
X19513Y-674519D01*
X20020Y-674436D01*
X20653Y-674603D01*
X21096Y-675019D01*
X21223Y-675519D01*
X21160Y-676019D01*
X20906Y-676436D01*
X19640Y-677269D01*
X19070Y-677853D01*
X18690Y-678686D01*
X18563Y-679436D01*
X21223D01*
G01X23600Y-678436D02*
X23980Y-679019D01*
X24486Y-679353D01*
X25056Y-679436D01*
X25563Y-679353D01*
X26070Y-678936D01*
X26386Y-678436D01*
X26450Y-677936D01*
X26323Y-677353D01*
X25880Y-676936D01*
X25436Y-676769D01*
X24866D01*
G01X25436D02*
X25816Y-676519D01*
X26133Y-676103D01*
X26260Y-675603D01*
X26133Y-675103D01*
X25816Y-674686D01*
X25246Y-674436D01*
X24676Y-674519D01*
X24106Y-674853D01*
G01X30853Y-679436D02*
Y-674436D01*
X28510Y-678019D01*
X31676D01*
G01X33800Y-678686D02*
X34180Y-679103D01*
X34623Y-679353D01*
X35193Y-679436D01*
X35763Y-679269D01*
X36206Y-678936D01*
X36523Y-678353D01*
X36586Y-677686D01*
X36460Y-677019D01*
X36143Y-676603D01*
X35700Y-676269D01*
X35256Y-676186D01*
X34813Y-676269D01*
X34243Y-676603D01*
X34433Y-674436D01*
X36143D01*
G01X44190Y-679436D02*
Y-674436D01*
X46596D01*
G01X45710Y-676853D02*
X44190D01*
G01X48910Y-679436D02*
X50493Y-674436D01*
X52076Y-679436D01*
G01X51506Y-677686D02*
X49480D01*
G01X54263Y-679436D02*
X56923Y-674436D01*
G01X54263D02*
X56923Y-679436D01*
G01X60693Y-679603D02*
X60566Y-679519D01*
Y-679353D01*
X60693Y-679269D01*
X60820Y-679353D01*
Y-679519D01*
X60693Y-679603D01*
G01Y-677353D02*
X60566Y-677269D01*
Y-677103D01*
X60693Y-677019D01*
X60820Y-677103D01*
Y-677269D01*
X60693Y-677353D01*
G01X65476Y-681103D02*
X64843Y-680269D01*
X64526Y-679436D01*
Y-676103D01*
X64843Y-675269D01*
X65476Y-674436D01*
G01X70893D02*
X70386Y-674603D01*
X70006Y-675019D01*
X69753Y-675519D01*
X69563Y-676186D01*
X69500Y-676936D01*
X69563Y-677686D01*
X69753Y-678353D01*
X70006Y-678853D01*
X70386Y-679269D01*
X70893Y-679436D01*
X71400Y-679269D01*
X71780Y-678853D01*
X72033Y-678353D01*
X72223Y-677686D01*
X72286Y-676936D01*
X72223Y-676186D01*
X72033Y-675519D01*
X71780Y-675019D01*
X71400Y-674603D01*
X70893Y-674436D01*
G01X74600Y-678436D02*
X74980Y-679019D01*
X75486Y-679353D01*
X76056Y-679436D01*
X76563Y-679353D01*
X77070Y-678936D01*
X77386Y-678436D01*
X77450Y-677936D01*
X77323Y-677353D01*
X76880Y-676936D01*
X76436Y-676769D01*
X75866D01*
G01X76436D02*
X76816Y-676519D01*
X77133Y-676103D01*
X77260Y-675603D01*
X77133Y-675103D01*
X76816Y-674686D01*
X76246Y-674436D01*
X75676Y-674519D01*
X75106Y-674853D01*
G01X81410Y-681103D02*
X82043Y-680269D01*
X82360Y-679436D01*
Y-676103D01*
X82043Y-675269D01*
X81410Y-674436D01*
G01X84800Y-678436D02*
X85180Y-679019D01*
X85686Y-679353D01*
X86256Y-679436D01*
X86763Y-679353D01*
X87270Y-678936D01*
X87586Y-678436D01*
X87650Y-677936D01*
X87523Y-677353D01*
X87080Y-676936D01*
X86636Y-676769D01*
X86066D01*
G01X86636D02*
X87016Y-676519D01*
X87333Y-676103D01*
X87460Y-675603D01*
X87333Y-675103D01*
X87016Y-674686D01*
X86446Y-674436D01*
X85876Y-674519D01*
X85306Y-674853D01*
G01X90216Y-678853D02*
X90660Y-679269D01*
X91166Y-679436D01*
X91673Y-679269D01*
X92116Y-678769D01*
X92433Y-678019D01*
X92560Y-677269D01*
Y-676353D01*
X92433Y-675603D01*
X92116Y-674936D01*
X91736Y-674603D01*
X91293Y-674436D01*
X90786Y-674603D01*
X90406Y-674936D01*
X90153Y-675436D01*
X90026Y-676103D01*
X90153Y-676686D01*
X90470Y-677269D01*
X90850Y-677603D01*
X91293Y-677686D01*
X91800Y-677519D01*
X92180Y-677103D01*
X92560Y-676353D01*
G01X96266Y-679436D02*
X96393Y-678353D01*
X96583Y-677436D01*
X96836Y-676603D01*
X97153Y-675686D01*
X97660Y-674436D01*
X95126D01*
G01X100670Y-677769D02*
X102316D01*
G01X105200Y-678436D02*
X105580Y-679019D01*
X106086Y-679353D01*
X106656Y-679436D01*
X107163Y-679353D01*
X107670Y-678936D01*
X107986Y-678436D01*
X108050Y-677936D01*
X107923Y-677353D01*
X107480Y-676936D01*
X107036Y-676769D01*
X106466D01*
G01X107036D02*
X107416Y-676519D01*
X107733Y-676103D01*
X107860Y-675603D01*
X107733Y-675103D01*
X107416Y-674686D01*
X106846Y-674436D01*
X106276Y-674519D01*
X105706Y-674853D01*
G01X110490Y-677353D02*
X110933Y-676769D01*
X111313Y-676436D01*
X111820Y-676269D01*
X112263Y-676436D01*
X112580Y-676769D01*
X112833Y-677269D01*
X112896Y-677853D01*
X112833Y-678353D01*
X112580Y-678853D01*
X112200Y-679269D01*
X111756Y-679436D01*
X111250Y-679269D01*
X110806Y-678769D01*
X110553Y-678019D01*
X110490Y-677186D01*
X110616Y-676103D01*
X110806Y-675519D01*
X111123Y-674936D01*
X111566Y-674519D01*
X112010Y-674436D01*
X112453Y-674603D01*
X112770Y-675019D01*
G01X116793Y-679436D02*
Y-674436D01*
X116033Y-675436D01*
G01Y-679436D02*
X117553D01*
G01X122653D02*
Y-674436D01*
X120310Y-678019D01*
X123476D01*
G01X141693Y-609436D02*
Y-684436D01*
G01Y-659436D02*
X244693D01*
Y-634436D01*
G01X141693D02*
X244693D01*
G01X246693Y-609436D02*
Y-684436D01*
G01X244693Y-609436D02*
Y-684436D01*
G01X252200Y-669436D02*
Y-664436D01*
X253466D01*
X253973Y-664686D01*
X254353Y-665019D01*
X254670Y-665519D01*
X254923Y-666103D01*
X254986Y-666936D01*
X254923Y-667769D01*
X254670Y-668353D01*
X254353Y-668853D01*
X253973Y-669186D01*
X253466Y-669436D01*
X252200D01*
G01X257110D02*
X258693Y-664436D01*
X260276Y-669436D01*
G01X259706Y-667686D02*
X257680D01*
G01X263793Y-664436D02*
Y-669436D01*
G01X262336Y-664436D02*
X265250D01*
G01X270160Y-669436D02*
X267626D01*
Y-664436D01*
X270160D01*
G01X269146Y-666853D02*
X267626D01*
G01X273993Y-669603D02*
X273866Y-669519D01*
Y-669353D01*
X273993Y-669269D01*
X274120Y-669353D01*
Y-669519D01*
X273993Y-669603D01*
G01Y-667353D02*
X273866Y-667269D01*
Y-667103D01*
X273993Y-667019D01*
X274120Y-667103D01*
Y-667269D01*
X273993Y-667353D01*
G01X246693Y-659436D02*
X446693D01*
G01X252326Y-644436D02*
Y-639436D01*
X253846D01*
X254353Y-639686D01*
X254733Y-640269D01*
X254860Y-640936D01*
X254733Y-641603D01*
X254416Y-642103D01*
X253846Y-642353D01*
X252326D01*
G01X257553Y-644603D02*
X259833Y-639436D01*
G01X262336Y-644436D02*
Y-639436D01*
X265250Y-644436D01*
Y-639436D01*
G01X268893Y-644603D02*
X268766Y-644519D01*
Y-644353D01*
X268893Y-644269D01*
X269020Y-644353D01*
Y-644519D01*
X268893Y-644603D01*
G01Y-642353D02*
X268766Y-642269D01*
Y-642103D01*
X268893Y-642019D01*
X269020Y-642103D01*
Y-642269D01*
X268893Y-642353D01*
G01X246693Y-634436D02*
X446693D01*
G01X252326Y-619436D02*
Y-614436D01*
X253846D01*
X254353Y-614686D01*
X254733Y-615269D01*
X254860Y-615936D01*
X254733Y-616603D01*
X254416Y-617103D01*
X253846Y-617353D01*
X252326D01*
G01X257426Y-619436D02*
Y-614436D01*
X259010D01*
X259516Y-614686D01*
X259833Y-615019D01*
X259960Y-615686D01*
X259833Y-616353D01*
X259453Y-616769D01*
X259010Y-617019D01*
X257426D01*
G01X259010D02*
X259960Y-619436D01*
G01X263793D02*
X263286Y-619353D01*
X262843Y-619019D01*
X262463Y-618519D01*
X262210Y-617936D01*
X262083Y-617269D01*
Y-616603D01*
X262210Y-615936D01*
X262463Y-615353D01*
X262843Y-614853D01*
X263286Y-614519D01*
X263793Y-614436D01*
X264300Y-614519D01*
X264743Y-614853D01*
X265123Y-615353D01*
X265376Y-615936D01*
X265503Y-616603D01*
Y-617269D01*
X265376Y-617936D01*
X265123Y-618519D01*
X264743Y-619019D01*
X264300Y-619353D01*
X263793Y-619436D01*
G01X267626Y-618436D02*
X267943Y-618936D01*
X268323Y-619269D01*
X268766Y-619436D01*
X269273Y-619269D01*
X269653Y-618936D01*
X270033Y-618436D01*
X270160Y-617769D01*
Y-614436D01*
G01X275260Y-619436D02*
X272726D01*
Y-614436D01*
X275260D01*
G01X274246Y-616853D02*
X272726D01*
G01X280486Y-614853D02*
X280106Y-614603D01*
X279663Y-614436D01*
X279156D01*
X278586Y-614686D01*
X278143Y-615103D01*
X277826Y-615603D01*
X277573Y-616436D01*
X277510Y-617186D01*
X277636Y-617936D01*
X277826Y-618436D01*
X278206Y-618936D01*
X278650Y-619269D01*
X279093Y-619436D01*
X279536D01*
X279980Y-619269D01*
X280360Y-619019D01*
X280676Y-618686D01*
G01X284193Y-614436D02*
Y-619436D01*
G01X282736Y-614436D02*
X285650D01*
G01X289293Y-619603D02*
X289166Y-619519D01*
Y-619353D01*
X289293Y-619269D01*
X289420Y-619353D01*
Y-619519D01*
X289293Y-619603D01*
G01Y-617353D02*
X289166Y-617269D01*
Y-617103D01*
X289293Y-617019D01*
X289420Y-617103D01*
Y-617269D01*
X289293Y-617353D01*
G01X361693Y-659436D02*
Y-684436D01*
G01X364326Y-661936D02*
Y-666936D01*
X366860D01*
G01X369933Y-661936D02*
X371453D01*
G01X370693D02*
Y-666936D01*
G01X369933D02*
X371453D01*
G01X376300Y-664269D02*
X376553Y-664019D01*
X376743Y-663603D01*
X376870Y-663019D01*
X376743Y-662519D01*
X376490Y-662186D01*
X376046Y-661936D01*
X374336D01*
Y-666936D01*
X376426D01*
X376870Y-666603D01*
X377123Y-666103D01*
X377250Y-665519D01*
X377123Y-664936D01*
X376743Y-664436D01*
X376300Y-664269D01*
X374336D01*
G01X380893Y-667103D02*
X380766Y-667019D01*
Y-666853D01*
X380893Y-666769D01*
X381020Y-666853D01*
Y-667019D01*
X380893Y-667103D01*
G01Y-664853D02*
X380766Y-664769D01*
Y-664603D01*
X380893Y-664519D01*
X381020Y-664603D01*
Y-664769D01*
X380893Y-664853D01*
G01X404693Y-659436D02*
Y-684436D01*
G01Y-634436D02*
Y-659436D01*
G01X412706Y-687603D02*
X412813Y-687478D01*
X412893Y-687269D01*
X412946Y-686978D01*
X412893Y-686728D01*
X412786Y-686561D01*
X412600Y-686436D01*
X411880D01*
Y-688936D01*
X412760D01*
X412946Y-688769D01*
X413053Y-688519D01*
X413106Y-688228D01*
X413053Y-687936D01*
X412893Y-687686D01*
X412706Y-687603D01*
X411880D01*
G01X415173Y-688936D02*
Y-687269D01*
G01Y-687561D02*
X415066Y-687394D01*
X414906Y-687311D01*
X414720Y-687269D01*
X414533Y-687353D01*
X414373Y-687519D01*
X414266Y-687769D01*
X414213Y-688103D01*
X414266Y-688436D01*
X414373Y-688686D01*
X414533Y-688853D01*
X414720Y-688936D01*
X414906Y-688894D01*
X415066Y-688769D01*
X415173Y-688603D01*
G01X416493Y-688644D02*
X416626Y-688811D01*
X416813Y-688936D01*
X416973D01*
X417133Y-688853D01*
X417240Y-688728D01*
X417293Y-688561D01*
X417266Y-688311D01*
X417160Y-688186D01*
X416680Y-687936D01*
X416573Y-687644D01*
X416626Y-687436D01*
X416733Y-687311D01*
X416893Y-687269D01*
X417053Y-687311D01*
X417213Y-687436D01*
G01X418693Y-687811D02*
X419546D01*
X419466Y-687519D01*
X419333Y-687353D01*
X419146Y-687269D01*
X418960Y-687311D01*
X418800Y-687436D01*
X418693Y-687728D01*
X418640Y-687978D01*
Y-688228D01*
X418693Y-688478D01*
X418826Y-688728D01*
X418986Y-688894D01*
X419173Y-688936D01*
X419360Y-688853D01*
X419546Y-688603D01*
G01X420813Y-688936D02*
Y-686436D01*
G01Y-687686D02*
X420946Y-687436D01*
X421106Y-687311D01*
X421266Y-687269D01*
X421506Y-687353D01*
X421666Y-687519D01*
X421773Y-687811D01*
Y-688144D01*
X421720Y-688478D01*
X421613Y-688728D01*
X421426Y-688894D01*
X421266Y-688936D01*
X421106Y-688894D01*
X420946Y-688769D01*
X420813Y-688561D01*
G01X423493Y-688936D02*
X423333Y-688894D01*
X423173Y-688728D01*
X423066Y-688436D01*
X423013Y-688103D01*
X423066Y-687769D01*
X423173Y-687478D01*
X423333Y-687311D01*
X423493Y-687269D01*
X423653Y-687311D01*
X423813Y-687478D01*
X423920Y-687769D01*
X423946Y-688103D01*
X423920Y-688436D01*
X423813Y-688728D01*
X423653Y-688894D01*
X423493Y-688936D01*
G01X426173D02*
Y-687269D01*
G01Y-687561D02*
X426066Y-687394D01*
X425906Y-687311D01*
X425720Y-687269D01*
X425533Y-687353D01*
X425373Y-687519D01*
X425266Y-687769D01*
X425213Y-688103D01*
X425266Y-688436D01*
X425373Y-688686D01*
X425533Y-688853D01*
X425720Y-688936D01*
X425906Y-688894D01*
X426066Y-688769D01*
X426173Y-688603D01*
G01X427520Y-688936D02*
Y-687269D01*
G01Y-687603D02*
X427653Y-687436D01*
X427786Y-687311D01*
X427973Y-687269D01*
X428106Y-687311D01*
X428266Y-687436D01*
G01X430573Y-686436D02*
Y-688936D01*
G01Y-688561D02*
X430466Y-688769D01*
X430306Y-688894D01*
X430120Y-688936D01*
X429906Y-688853D01*
X429746Y-688644D01*
X429640Y-688394D01*
X429613Y-688103D01*
X429640Y-687811D01*
X429746Y-687561D01*
X429906Y-687353D01*
X430120Y-687269D01*
X430306Y-687311D01*
X430440Y-687394D01*
X430573Y-687561D01*
G01X433960Y-688936D02*
Y-686436D01*
X434626D01*
X434840Y-686561D01*
X434973Y-686728D01*
X435026Y-687061D01*
X434973Y-687394D01*
X434813Y-687603D01*
X434626Y-687728D01*
X433960D01*
G01X434626D02*
X435026Y-688936D01*
G01X436293Y-687811D02*
X437146D01*
X437066Y-687519D01*
X436933Y-687353D01*
X436746Y-687269D01*
X436560Y-687311D01*
X436400Y-687436D01*
X436293Y-687728D01*
X436240Y-687978D01*
Y-688228D01*
X436293Y-688478D01*
X436426Y-688728D01*
X436586Y-688894D01*
X436773Y-688936D01*
X436960Y-688853D01*
X437146Y-688603D01*
G01X438413Y-687269D02*
X438893Y-688936D01*
X439373Y-687269D01*
G01X441093Y-689019D02*
X441040Y-688978D01*
Y-688894D01*
X441093Y-688853D01*
X441146Y-688894D01*
Y-688978D01*
X441093Y-689019D01*
G01X443613Y-688936D02*
Y-686436D01*
X442626Y-688228D01*
X443960D01*
G01X444826Y-688936D02*
X445493Y-686436D01*
X446160Y-688936D01*
G01X445920Y-688061D02*
X445066D01*
G01X408593Y-661936D02*
Y-666936D01*
G01X407136Y-661936D02*
X410050D01*
G01X413693Y-666936D02*
X413313Y-666853D01*
X412933Y-666519D01*
X412680Y-665936D01*
X412553Y-665269D01*
X412680Y-664603D01*
X412933Y-664019D01*
X413313Y-663686D01*
X413693Y-663603D01*
X414073Y-663686D01*
X414453Y-664019D01*
X414706Y-664603D01*
X414770Y-665269D01*
X414706Y-665936D01*
X414453Y-666519D01*
X414073Y-666853D01*
X413693Y-666936D01*
G01X418793D02*
X418413Y-666853D01*
X418033Y-666519D01*
X417780Y-665936D01*
X417653Y-665269D01*
X417780Y-664603D01*
X418033Y-664019D01*
X418413Y-663686D01*
X418793Y-663603D01*
X419173Y-663686D01*
X419553Y-664019D01*
X419806Y-664603D01*
X419870Y-665269D01*
X419806Y-665936D01*
X419553Y-666519D01*
X419173Y-666853D01*
X418793Y-666936D01*
G01X423893D02*
Y-661936D01*
G01X428993Y-667103D02*
X428866Y-667019D01*
Y-666853D01*
X428993Y-666769D01*
X429120Y-666853D01*
Y-667019D01*
X428993Y-667103D01*
G01Y-664853D02*
X428866Y-664769D01*
Y-664603D01*
X428993Y-664519D01*
X429120Y-664603D01*
Y-664769D01*
X428993Y-664853D01*
G01X407326Y-641936D02*
Y-636936D01*
X408910D01*
X409416Y-637186D01*
X409733Y-637519D01*
X409860Y-638186D01*
X409733Y-638853D01*
X409353Y-639269D01*
X408910Y-639519D01*
X407326D01*
G01X408910D02*
X409860Y-641936D01*
G01X414960D02*
X412426D01*
Y-636936D01*
X414960D01*
G01X413946Y-639353D02*
X412426D01*
G01X417210Y-636936D02*
X418793Y-641936D01*
X420376Y-636936D01*
G01X423893Y-642103D02*
X423766Y-642019D01*
Y-641853D01*
X423893Y-641769D01*
X424020Y-641853D01*
Y-642019D01*
X423893Y-642103D01*
G01Y-639853D02*
X423766Y-639769D01*
Y-639603D01*
X423893Y-639519D01*
X424020Y-639603D01*
Y-639769D01*
X423893Y-639853D01*
G01X2010999Y-388000D02*
Y1475775D01*
X-407000D01*
Y-386798D01*
Y-755294D01*
Y-793716D01*
X-368578D01*
X1942346D01*
X2010999D01*
Y-725063D01*
Y-388000D01*
G01X-42602Y-671096D02*
X-41975Y-671621D01*
X-41270Y-671936D01*
X-40644D01*
X-40017Y-671621D01*
X-39547Y-671096D01*
X-39312Y-670361D01*
X-39469Y-669626D01*
X-39860Y-668996D01*
X-40565Y-668576D01*
X-41505Y-668366D01*
X-42054Y-667946D01*
X-42289Y-667211D01*
X-42132Y-666476D01*
X-41740Y-665951D01*
X-41192Y-665636D01*
X-40644D01*
X-40095Y-665846D01*
X-39625Y-666371D01*
G01X-36302Y-671936D02*
Y-665636D01*
G01X-33012D02*
Y-671936D01*
G01Y-668786D02*
X-36302D01*
G01X-29297Y-665636D02*
X-27417D01*
G01X-28357D02*
Y-671936D01*
G01X-29297D02*
X-27417D01*
G01X-20490D02*
X-23624D01*
Y-665636D01*
X-20490D01*
G01X-21744Y-668681D02*
X-23624D01*
G01X-17559Y-671936D02*
Y-665636D01*
X-13955Y-671936D01*
Y-665636D01*
G01X-9614Y-673091D02*
X-9300Y-671726D01*
G01X-3157Y-665636D02*
Y-671936D01*
G01X-4959Y-665636D02*
X-1355D01*
G01X1185Y-671936D02*
X3143Y-665636D01*
X5101Y-671936D01*
G01X4396Y-669731D02*
X1890D01*
G01X8503Y-665636D02*
X10383D01*
G01X9443D02*
Y-671936D01*
G01X8503D02*
X10383D01*
G01X13393Y-665636D02*
X14490Y-671936D01*
X15743Y-665636D01*
X16996Y-671936D01*
X18093Y-665636D01*
G01X20085Y-671936D02*
X22043Y-665636D01*
X24001Y-671936D01*
G01X23296Y-669731D02*
X20790D01*
G01X26541Y-671936D02*
Y-665636D01*
X30145Y-671936D01*
Y-665636D01*
G01X39376Y-671936D02*
Y-665636D01*
X41335D01*
X41961Y-665951D01*
X42353Y-666371D01*
X42510Y-667211D01*
X42353Y-668051D01*
X41883Y-668576D01*
X41335Y-668891D01*
X39376D01*
G01X41335D02*
X42510Y-671936D01*
G01X47243Y-672146D02*
X47086Y-672041D01*
Y-671831D01*
X47243Y-671726D01*
X47400Y-671831D01*
Y-672041D01*
X47243Y-672146D01*
G01X53543Y-671936D02*
X52916Y-671831D01*
X52368Y-671411D01*
X51898Y-670781D01*
X51585Y-670046D01*
X51428Y-669206D01*
Y-668366D01*
X51585Y-667526D01*
X51898Y-666791D01*
X52368Y-666161D01*
X52916Y-665741D01*
X53543Y-665636D01*
X54170Y-665741D01*
X54718Y-666161D01*
X55188Y-666791D01*
X55501Y-667526D01*
X55658Y-668366D01*
Y-669206D01*
X55501Y-670046D01*
X55188Y-670781D01*
X54718Y-671411D01*
X54170Y-671831D01*
X53543Y-671936D01*
G01X59843Y-672146D02*
X59686Y-672041D01*
Y-671831D01*
X59843Y-671726D01*
X60000Y-671831D01*
Y-672041D01*
X59843Y-672146D01*
G01X67866Y-666161D02*
X67396Y-665846D01*
X66848Y-665636D01*
X66221D01*
X65516Y-665951D01*
X64968Y-666476D01*
X64576Y-667106D01*
X64263Y-668156D01*
X64185Y-669101D01*
X64341Y-670046D01*
X64576Y-670676D01*
X65046Y-671306D01*
X65595Y-671726D01*
X66143Y-671936D01*
X66691D01*
X67240Y-671726D01*
X67710Y-671411D01*
X68101Y-670991D01*
G01X72443Y-672146D02*
X72286Y-672041D01*
Y-671831D01*
X72443Y-671726D01*
X72600Y-671831D01*
Y-672041D01*
X72443Y-672146D01*
G01X-42680Y-661936D02*
Y-655636D01*
G01X-39704D02*
X-42680Y-659521D01*
G01X-39234Y-661936D02*
X-41349Y-657736D01*
G01X-36380Y-655636D02*
Y-660151D01*
X-36067Y-661096D01*
X-35440Y-661726D01*
X-34657Y-661936D01*
X-33874Y-661726D01*
X-33247Y-661096D01*
X-32934Y-660151D01*
Y-655636D01*
G01X-26790Y-661936D02*
X-29924D01*
Y-655636D01*
X-26790D01*
G01X-28044Y-658681D02*
X-29924D01*
G01X-22997Y-655636D02*
X-21117D01*
G01X-22057D02*
Y-661936D01*
G01X-22997D02*
X-21117D01*
G01X-11102Y-661096D02*
X-10475Y-661621D01*
X-9770Y-661936D01*
X-9144D01*
X-8517Y-661621D01*
X-8047Y-661096D01*
X-7812Y-660361D01*
X-7969Y-659626D01*
X-8360Y-658996D01*
X-9065Y-658576D01*
X-10005Y-658366D01*
X-10554Y-657946D01*
X-10789Y-657211D01*
X-10632Y-656476D01*
X-10240Y-655951D01*
X-9692Y-655636D01*
X-9144D01*
X-8595Y-655846D01*
X-8125Y-656371D01*
G01X-4802Y-661936D02*
Y-655636D01*
G01X-1512D02*
Y-661936D01*
G01Y-658786D02*
X-4802D01*
G01X1185Y-661936D02*
X3143Y-655636D01*
X5101Y-661936D01*
G01X4396Y-659731D02*
X1890D01*
G01X7641Y-661936D02*
Y-655636D01*
X11245Y-661936D01*
Y-655636D01*
G01X20398Y-661936D02*
Y-655636D01*
G01X23688D02*
Y-661936D01*
G01Y-658786D02*
X20398D01*
G01X26698Y-661096D02*
X27325Y-661621D01*
X28030Y-661936D01*
X28656D01*
X29283Y-661621D01*
X29753Y-661096D01*
X29988Y-660361D01*
X29831Y-659626D01*
X29440Y-658996D01*
X28735Y-658576D01*
X27795Y-658366D01*
X27246Y-657946D01*
X27011Y-657211D01*
X27168Y-656476D01*
X27560Y-655951D01*
X28108Y-655636D01*
X28656D01*
X29205Y-655846D01*
X29675Y-656371D01*
G01X33703Y-655636D02*
X35583D01*
G01X34643D02*
Y-661936D01*
G01X33703D02*
X35583D01*
G01X38985D02*
X40943Y-655636D01*
X42901Y-661936D01*
G01X42196Y-659731D02*
X39690D01*
G01X45441Y-661936D02*
Y-655636D01*
X49045Y-661936D01*
Y-655636D01*
G01X54013Y-658786D02*
X55580D01*
Y-660676D01*
X55110Y-661306D01*
X54561Y-661726D01*
X53778Y-661936D01*
X52995Y-661726D01*
X52446Y-661306D01*
X51976Y-660676D01*
X51663Y-659941D01*
X51506Y-659101D01*
Y-658366D01*
X51663Y-657736D01*
X51976Y-657001D01*
X52446Y-656371D01*
X52916Y-655951D01*
X53543Y-655636D01*
X54091D01*
X54718Y-655846D01*
X55188Y-656266D01*
G01X59686Y-663091D02*
X60000Y-661726D01*
G01X66143Y-655636D02*
Y-661936D01*
G01X64341Y-655636D02*
X67945D01*
G01X70485Y-661936D02*
X72443Y-655636D01*
X74401Y-661936D01*
G01X73696Y-659731D02*
X71190D01*
G01X78743Y-661936D02*
X78116Y-661831D01*
X77568Y-661411D01*
X77098Y-660781D01*
X76785Y-660046D01*
X76628Y-659206D01*
Y-658366D01*
X76785Y-657526D01*
X77098Y-656791D01*
X77568Y-656161D01*
X78116Y-655741D01*
X78743Y-655636D01*
X79370Y-655741D01*
X79918Y-656161D01*
X80388Y-656791D01*
X80701Y-657526D01*
X80858Y-658366D01*
Y-659206D01*
X80701Y-660046D01*
X80388Y-660781D01*
X79918Y-661411D01*
X79370Y-661831D01*
X78743Y-661936D01*
G01X91343D02*
Y-659101D01*
X89776Y-655636D01*
G01X92910D02*
X91343Y-659101D01*
G01X95920Y-655636D02*
Y-660151D01*
X96233Y-661096D01*
X96860Y-661726D01*
X97643Y-661936D01*
X98426Y-661726D01*
X99053Y-661096D01*
X99366Y-660151D01*
Y-655636D01*
G01X101985Y-661936D02*
X103943Y-655636D01*
X105901Y-661936D01*
G01X105196Y-659731D02*
X102690D01*
G01X108441Y-661936D02*
Y-655636D01*
X112045Y-661936D01*
Y-655636D01*
G01X-42759Y-651936D02*
Y-645636D01*
X-39155Y-651936D01*
Y-645636D01*
G01X-34657Y-651936D02*
X-35284Y-651831D01*
X-35832Y-651411D01*
X-36302Y-650781D01*
X-36615Y-650046D01*
X-36772Y-649206D01*
Y-648366D01*
X-36615Y-647526D01*
X-36302Y-646791D01*
X-35832Y-646161D01*
X-35284Y-645741D01*
X-34657Y-645636D01*
X-34030Y-645741D01*
X-33482Y-646161D01*
X-33012Y-646791D01*
X-32699Y-647526D01*
X-32542Y-648366D01*
Y-649206D01*
X-32699Y-650046D01*
X-33012Y-650781D01*
X-33482Y-651411D01*
X-34030Y-651831D01*
X-34657Y-651936D01*
G01X-28357Y-652146D02*
X-28514Y-652041D01*
Y-651831D01*
X-28357Y-651726D01*
X-28200Y-651831D01*
Y-652041D01*
X-28357Y-652146D01*
G01X-22057Y-651936D02*
Y-645636D01*
X-22997Y-646896D01*
G01Y-651936D02*
X-21117D01*
G01X-15757D02*
X-15209Y-651831D01*
X-14582Y-651516D01*
X-14190Y-650991D01*
X-14034Y-650256D01*
X-14190Y-649521D01*
X-14660Y-648891D01*
X-15365Y-648576D01*
X-16149D01*
X-16619Y-648366D01*
X-17010Y-647841D01*
X-17167Y-647106D01*
X-16932Y-646371D01*
X-16384Y-645846D01*
X-15757Y-645636D01*
X-15130Y-645846D01*
X-14582Y-646371D01*
X-14347Y-647106D01*
X-14504Y-647841D01*
X-14895Y-648366D01*
X-15365Y-648576D01*
X-16149D01*
X-16854Y-648891D01*
X-17324Y-649521D01*
X-17480Y-650256D01*
X-17324Y-650991D01*
X-16932Y-651516D01*
X-16305Y-651831D01*
X-15757Y-651936D01*
G01X-9457D02*
X-8909Y-651831D01*
X-8282Y-651516D01*
X-7890Y-650991D01*
X-7734Y-650256D01*
X-7890Y-649521D01*
X-8360Y-648891D01*
X-9065Y-648576D01*
X-9849D01*
X-10319Y-648366D01*
X-10710Y-647841D01*
X-10867Y-647106D01*
X-10632Y-646371D01*
X-10084Y-645846D01*
X-9457Y-645636D01*
X-8830Y-645846D01*
X-8282Y-646371D01*
X-8047Y-647106D01*
X-8204Y-647841D01*
X-8595Y-648366D01*
X-9065Y-648576D01*
X-9849D01*
X-10554Y-648891D01*
X-11024Y-649521D01*
X-11180Y-650256D01*
X-11024Y-650991D01*
X-10632Y-651516D01*
X-10005Y-651831D01*
X-9457Y-651936D01*
G01X-3314Y-653091D02*
X-3000Y-651726D01*
G01X793Y-645636D02*
X1890Y-651936D01*
X3143Y-645636D01*
X4396Y-651936D01*
X5493Y-645636D01*
G01X11010Y-651936D02*
X7876D01*
Y-645636D01*
X11010D01*
G01X9756Y-648681D02*
X7876D01*
G01X13941Y-651936D02*
Y-645636D01*
X17545Y-651936D01*
Y-645636D01*
G01X26698Y-651936D02*
Y-645636D01*
G01X29988D02*
Y-651936D01*
G01Y-648786D02*
X26698D01*
G01X32293Y-645636D02*
X33390Y-651936D01*
X34643Y-645636D01*
X35896Y-651936D01*
X36993Y-645636D01*
G01X38985Y-651936D02*
X40943Y-645636D01*
X42901Y-651936D01*
G01X42196Y-649731D02*
X39690D01*
G01X52055Y-646686D02*
X52525Y-646056D01*
X53073Y-645741D01*
X53700Y-645636D01*
X54483Y-645846D01*
X55031Y-646371D01*
X55188Y-647001D01*
X55110Y-647631D01*
X54796Y-648156D01*
X53230Y-649206D01*
X52525Y-649941D01*
X52055Y-650991D01*
X51898Y-651936D01*
X55188D01*
G01X58041D02*
Y-645636D01*
X61645Y-651936D01*
Y-645636D01*
G01X64420Y-651936D02*
Y-645636D01*
X65986D01*
X66613Y-645951D01*
X67083Y-646371D01*
X67475Y-647001D01*
X67788Y-647736D01*
X67866Y-648786D01*
X67788Y-649836D01*
X67475Y-650571D01*
X67083Y-651201D01*
X66613Y-651621D01*
X65986Y-651936D01*
X64420D01*
G01X77176D02*
Y-645636D01*
X79135D01*
X79761Y-645951D01*
X80153Y-646371D01*
X80310Y-647211D01*
X80153Y-648051D01*
X79683Y-648576D01*
X79135Y-648891D01*
X77176D01*
G01X79135D02*
X80310Y-651936D01*
G01X83320D02*
Y-645636D01*
X84886D01*
X85513Y-645951D01*
X85983Y-646371D01*
X86375Y-647001D01*
X86688Y-647736D01*
X86766Y-648786D01*
X86688Y-649836D01*
X86375Y-650571D01*
X85983Y-651201D01*
X85513Y-651621D01*
X84886Y-651936D01*
X83320D01*
G01X91343Y-652146D02*
X91186Y-652041D01*
Y-651831D01*
X91343Y-651726D01*
X91500Y-651831D01*
Y-652041D01*
X91343Y-652146D01*
G01X-18657Y-639236D02*
X-21177Y-638819D01*
X-23382Y-637153D01*
X-25272Y-634653D01*
X-26532Y-631736D01*
X-27162Y-628403D01*
Y-625069D01*
X-26532Y-621736D01*
X-25272Y-618819D01*
X-23382Y-616320D01*
X-21177Y-614653D01*
X-18657Y-614236D01*
X-16137Y-614653D01*
X-13932Y-616320D01*
X-12042Y-618819D01*
X-10782Y-621736D01*
X-10152Y-625069D01*
Y-628403D01*
X-10782Y-631736D01*
X-12042Y-634653D01*
X-13932Y-637153D01*
X-16137Y-638819D01*
X-18657Y-639236D01*
G01X-16137Y-632569D02*
X-12357Y-639236D01*
G01X1188Y-622570D02*
Y-634236D01*
X2448Y-637153D01*
X4338Y-638819D01*
X6543Y-639236D01*
X8748Y-638819D01*
X10638Y-637153D01*
X11898Y-634236D01*
G01Y-639236D02*
Y-622570D01*
G01X37413Y-639236D02*
Y-622570D01*
G01Y-625486D02*
X36153Y-623820D01*
X34263Y-622986D01*
X32058Y-622570D01*
X29853Y-623403D01*
X27963Y-625069D01*
X26703Y-627570D01*
X26073Y-630903D01*
X26703Y-634236D01*
X27963Y-636737D01*
X29853Y-638403D01*
X32058Y-639236D01*
X34263Y-638819D01*
X36153Y-637570D01*
X37413Y-635903D01*
G01X51588Y-639236D02*
Y-622570D01*
G01Y-626736D02*
X52848Y-624653D01*
X54738Y-622986D01*
X57258Y-622570D01*
X59463Y-622986D01*
X61353Y-624653D01*
X62298Y-627570D01*
Y-639236D01*
G01X82143Y-614236D02*
Y-639236D01*
G01X77733Y-622570D02*
X86553D01*
G01X113013Y-639236D02*
Y-622570D01*
G01Y-625486D02*
X111753Y-623820D01*
X109863Y-622986D01*
X107658Y-622570D01*
X105453Y-623403D01*
X103563Y-625069D01*
X102303Y-627570D01*
X101673Y-630903D01*
X102303Y-634236D01*
X103563Y-636737D01*
X105453Y-638403D01*
X107658Y-639236D01*
X109863Y-638819D01*
X111753Y-637570D01*
X113013Y-635903D01*
G01X152693Y-618936D02*
Y-626936D01*
X156693D01*
G01X164493D02*
Y-621603D01*
G01Y-622536D02*
X164093Y-622003D01*
X163493Y-621736D01*
X162793Y-621603D01*
X162093Y-621869D01*
X161493Y-622403D01*
X161093Y-623203D01*
X160893Y-624269D01*
X161093Y-625336D01*
X161493Y-626136D01*
X162093Y-626669D01*
X162793Y-626936D01*
X163493Y-626803D01*
X164093Y-626403D01*
X164493Y-625870D01*
G01X168593Y-629336D02*
X169193Y-629603D01*
X169993Y-629336D01*
X170493Y-628803D01*
X170893Y-628136D01*
X171493Y-626003D01*
X172793Y-621603D01*
G01X169593D02*
X171493Y-626003D01*
G01X177193Y-623336D02*
X180393D01*
X180093Y-622403D01*
X179593Y-621869D01*
X178893Y-621603D01*
X178193Y-621736D01*
X177593Y-622136D01*
X177193Y-623069D01*
X176993Y-623870D01*
Y-624669D01*
X177193Y-625469D01*
X177693Y-626269D01*
X178293Y-626803D01*
X178993Y-626936D01*
X179693Y-626669D01*
X180393Y-625870D01*
G01X185293Y-626936D02*
Y-621603D01*
G01Y-622669D02*
X185793Y-622136D01*
X186293Y-621736D01*
X186993Y-621603D01*
X187493Y-621736D01*
X188093Y-622136D01*
G01X166093Y-651936D02*
Y-643936D01*
X168693Y-650603D01*
X171293Y-643936D01*
Y-651936D01*
G01X174193D02*
X176693Y-643936D01*
X179193Y-651936D01*
G01X178293Y-649136D02*
X175093D01*
G01X182593Y-650870D02*
X183393Y-651536D01*
X184293Y-651936D01*
X185093D01*
X185893Y-651536D01*
X186493Y-650870D01*
X186793Y-649936D01*
X186593Y-649003D01*
X186093Y-648203D01*
X185193Y-647669D01*
X183993Y-647403D01*
X183293Y-646869D01*
X182993Y-645936D01*
X183193Y-645003D01*
X183693Y-644336D01*
X184393Y-643936D01*
X185093D01*
X185793Y-644203D01*
X186393Y-644869D01*
G01X190493Y-651936D02*
Y-643936D01*
G01X194293D02*
X190493Y-648870D01*
G01X194893Y-651936D02*
X192193Y-646603D01*
G01X199393Y-649269D02*
X201993D01*
G01X209493Y-647669D02*
X209893Y-647269D01*
X210193Y-646603D01*
X210393Y-645669D01*
X210193Y-644869D01*
X209793Y-644336D01*
X209093Y-643936D01*
X206393D01*
Y-651936D01*
X209693D01*
X210393Y-651403D01*
X210793Y-650603D01*
X210993Y-649669D01*
X210793Y-648736D01*
X210193Y-647936D01*
X209493Y-647669D01*
X206393D01*
G01X216693Y-651936D02*
X215893Y-651803D01*
X215193Y-651269D01*
X214593Y-650469D01*
X214193Y-649536D01*
X213993Y-648469D01*
Y-647403D01*
X214193Y-646336D01*
X214593Y-645403D01*
X215193Y-644603D01*
X215893Y-644069D01*
X216693Y-643936D01*
X217493Y-644069D01*
X218193Y-644603D01*
X218793Y-645403D01*
X219193Y-646336D01*
X219393Y-647403D01*
Y-648469D01*
X219193Y-649536D01*
X218793Y-650469D01*
X218193Y-651269D01*
X217493Y-651803D01*
X216693Y-651936D01*
G01X224693Y-643936D02*
Y-651936D01*
G01X222393Y-643936D02*
X226993D01*
G01X173993Y-676936D02*
Y-668936D01*
G01X177793D02*
X173993Y-673870D01*
G01X178393Y-676936D02*
X175693Y-671603D01*
G01X185993Y-676936D02*
Y-671603D01*
G01Y-672536D02*
X185593Y-672003D01*
X184993Y-671736D01*
X184293Y-671603D01*
X183593Y-671869D01*
X182993Y-672403D01*
X182593Y-673203D01*
X182393Y-674269D01*
X182593Y-675336D01*
X182993Y-676136D01*
X183593Y-676669D01*
X184293Y-676936D01*
X184993Y-676803D01*
X185593Y-676403D01*
X185993Y-675870D01*
G01X192193Y-671603D02*
Y-676936D01*
G01Y-669469D02*
X191993Y-669336D01*
Y-669069D01*
X192193Y-668936D01*
X192393Y-669069D01*
Y-669336D01*
X192193Y-669469D01*
G01X279293Y-670269D02*
X279893Y-669469D01*
X280593Y-669069D01*
X281393Y-668936D01*
X282393Y-669203D01*
X283093Y-669869D01*
X283293Y-670669D01*
X283193Y-671470D01*
X282793Y-672136D01*
X280793Y-673469D01*
X279893Y-674403D01*
X279293Y-675736D01*
X279093Y-676936D01*
X283293D01*
G01X289193Y-668936D02*
X288393Y-669203D01*
X287793Y-669869D01*
X287393Y-670669D01*
X287093Y-671736D01*
X286993Y-672936D01*
X287093Y-674136D01*
X287393Y-675203D01*
X287793Y-676003D01*
X288393Y-676669D01*
X289193Y-676936D01*
X289993Y-676669D01*
X290593Y-676003D01*
X290993Y-675203D01*
X291293Y-674136D01*
X291393Y-672936D01*
X291293Y-671736D01*
X290993Y-670669D01*
X290593Y-669869D01*
X289993Y-669203D01*
X289193Y-668936D01*
G01X295293Y-670269D02*
X295893Y-669469D01*
X296593Y-669069D01*
X297393Y-668936D01*
X298393Y-669203D01*
X299093Y-669869D01*
X299293Y-670669D01*
X299193Y-671470D01*
X298793Y-672136D01*
X296793Y-673469D01*
X295893Y-674403D01*
X295293Y-675736D01*
X295093Y-676936D01*
X299293D01*
G01X303293Y-670269D02*
X303893Y-669469D01*
X304593Y-669069D01*
X305393Y-668936D01*
X306393Y-669203D01*
X307093Y-669869D01*
X307293Y-670669D01*
X307193Y-671470D01*
X306793Y-672136D01*
X304793Y-673469D01*
X303893Y-674403D01*
X303293Y-675736D01*
X303093Y-676936D01*
X307293D01*
G01X311393Y-677203D02*
X314993Y-668936D01*
G01X321193Y-676936D02*
Y-668936D01*
X319993Y-670536D01*
G01Y-676936D02*
X322393D01*
G01X327293Y-670269D02*
X327893Y-669469D01*
X328593Y-669069D01*
X329393Y-668936D01*
X330393Y-669203D01*
X331093Y-669869D01*
X331293Y-670669D01*
X331193Y-671470D01*
X330793Y-672136D01*
X328793Y-673469D01*
X327893Y-674403D01*
X327293Y-675736D01*
X327093Y-676936D01*
X331293D01*
G01X335393Y-677203D02*
X338993Y-668936D01*
G01X345193D02*
X344393Y-669203D01*
X343793Y-669869D01*
X343393Y-670669D01*
X343093Y-671736D01*
X342993Y-672936D01*
X343093Y-674136D01*
X343393Y-675203D01*
X343793Y-676003D01*
X344393Y-676669D01*
X345193Y-676936D01*
X345993Y-676669D01*
X346593Y-676003D01*
X346993Y-675203D01*
X347293Y-674136D01*
X347393Y-672936D01*
X347293Y-671736D01*
X346993Y-670669D01*
X346593Y-669869D01*
X345993Y-669203D01*
X345193Y-668936D01*
G01X351493Y-676003D02*
X352193Y-676669D01*
X352993Y-676936D01*
X353793Y-676669D01*
X354493Y-675870D01*
X354993Y-674669D01*
X355193Y-673469D01*
Y-672003D01*
X354993Y-670803D01*
X354493Y-669736D01*
X353893Y-669203D01*
X353193Y-668936D01*
X352393Y-669203D01*
X351793Y-669736D01*
X351393Y-670536D01*
X351193Y-671603D01*
X351393Y-672536D01*
X351893Y-673469D01*
X352493Y-674003D01*
X353193Y-674136D01*
X353993Y-673870D01*
X354593Y-673203D01*
X355193Y-672003D01*
G01X278993Y-651936D02*
Y-643936D01*
X280993D01*
X281793Y-644336D01*
X282393Y-644869D01*
X282893Y-645669D01*
X283293Y-646603D01*
X283393Y-647936D01*
X283293Y-649269D01*
X282893Y-650203D01*
X282393Y-651003D01*
X281793Y-651536D01*
X280993Y-651936D01*
X278993D01*
G01X286693D02*
X289193Y-643936D01*
X291693Y-651936D01*
G01X290793Y-649136D02*
X287593D01*
G01X297193Y-643936D02*
X296393Y-644203D01*
X295793Y-644869D01*
X295393Y-645669D01*
X295093Y-646736D01*
X294993Y-647936D01*
X295093Y-649136D01*
X295393Y-650203D01*
X295793Y-651003D01*
X296393Y-651669D01*
X297193Y-651936D01*
X297993Y-651669D01*
X298593Y-651003D01*
X298993Y-650203D01*
X299293Y-649136D01*
X299393Y-647936D01*
X299293Y-646736D01*
X298993Y-645669D01*
X298593Y-644869D01*
X297993Y-644203D01*
X297193Y-643936D01*
G01X303293Y-651936D02*
Y-643936D01*
X307093D01*
G01X305693Y-647803D02*
X303293D01*
G01X313193Y-643936D02*
X312393Y-644203D01*
X311793Y-644869D01*
X311393Y-645669D01*
X311093Y-646736D01*
X310993Y-647936D01*
X311093Y-649136D01*
X311393Y-650203D01*
X311793Y-651003D01*
X312393Y-651669D01*
X313193Y-651936D01*
X313993Y-651669D01*
X314593Y-651003D01*
X314993Y-650203D01*
X315293Y-649136D01*
X315393Y-647936D01*
X315293Y-646736D01*
X314993Y-645669D01*
X314593Y-644869D01*
X313993Y-644203D01*
X313193Y-643936D01*
G01X321193D02*
Y-651936D01*
G01X318893Y-643936D02*
X323493D01*
G01X326593Y-651936D02*
Y-643936D01*
X329193Y-650603D01*
X331793Y-643936D01*
Y-651936D01*
G01X334993D02*
Y-643936D01*
X336993D01*
X337793Y-644336D01*
X338393Y-644869D01*
X338893Y-645669D01*
X339293Y-646603D01*
X339393Y-647936D01*
X339293Y-649269D01*
X338893Y-650203D01*
X338393Y-651003D01*
X337793Y-651536D01*
X336993Y-651936D01*
X334993D01*
G01X347393Y-644603D02*
X346793Y-644203D01*
X346093Y-643936D01*
X345293D01*
X344393Y-644336D01*
X343693Y-645003D01*
X343193Y-645803D01*
X342793Y-647136D01*
X342693Y-648336D01*
X342893Y-649536D01*
X343193Y-650336D01*
X343793Y-651136D01*
X344493Y-651669D01*
X345193Y-651936D01*
X345893D01*
X346593Y-651669D01*
X347193Y-651269D01*
X347693Y-650736D01*
G01X350993Y-651936D02*
Y-643936D01*
X352993D01*
X353793Y-644336D01*
X354393Y-644869D01*
X354893Y-645669D01*
X355293Y-646603D01*
X355393Y-647936D01*
X355293Y-649269D01*
X354893Y-650203D01*
X354393Y-651003D01*
X353793Y-651536D01*
X352993Y-651936D01*
X350993D01*
G01X361193Y-643936D02*
X360393Y-644203D01*
X359793Y-644869D01*
X359393Y-645669D01*
X359093Y-646736D01*
X358993Y-647936D01*
X359093Y-649136D01*
X359393Y-650203D01*
X359793Y-651003D01*
X360393Y-651669D01*
X361193Y-651936D01*
X361993Y-651669D01*
X362593Y-651003D01*
X362993Y-650203D01*
X363293Y-649136D01*
X363393Y-647936D01*
X363293Y-646736D01*
X362993Y-645669D01*
X362593Y-644869D01*
X361993Y-644203D01*
X361193Y-643936D01*
G01X298418Y-624819D02*
Y-618519D01*
X301394D01*
G01X300298Y-621564D02*
X298418D01*
G01X306206Y-618519D02*
X305579Y-618729D01*
X305109Y-619254D01*
X304796Y-619884D01*
X304561Y-620724D01*
X304483Y-621669D01*
X304561Y-622614D01*
X304796Y-623454D01*
X305109Y-624084D01*
X305579Y-624609D01*
X306206Y-624819D01*
X306833Y-624609D01*
X307303Y-624084D01*
X307616Y-623454D01*
X307851Y-622614D01*
X307929Y-621669D01*
X307851Y-620724D01*
X307616Y-619884D01*
X307303Y-619254D01*
X306833Y-618729D01*
X306206Y-618519D01*
G01X312506D02*
Y-624819D01*
G01X310704Y-618519D02*
X314308D01*
G01X316456Y-626919D02*
X321156D01*
G01X323069Y-624819D02*
Y-618519D01*
X325106Y-623769D01*
X327143Y-618519D01*
Y-624819D01*
G01X332816D02*
Y-620619D01*
G01Y-621354D02*
X332503Y-620934D01*
X332033Y-620724D01*
X331484Y-620619D01*
X330936Y-620829D01*
X330466Y-621249D01*
X330153Y-621879D01*
X329996Y-622719D01*
X330153Y-623559D01*
X330466Y-624189D01*
X330936Y-624609D01*
X331484Y-624819D01*
X332033Y-624714D01*
X332503Y-624399D01*
X332816Y-623979D01*
G01X336374Y-624819D02*
Y-620619D01*
G01Y-621669D02*
X336688Y-621144D01*
X337158Y-620724D01*
X337784Y-620619D01*
X338333Y-620724D01*
X338803Y-621144D01*
X339038Y-621879D01*
Y-624819D01*
G01X345416D02*
Y-620619D01*
G01Y-621354D02*
X345103Y-620934D01*
X344633Y-620724D01*
X344084Y-620619D01*
X343536Y-620829D01*
X343066Y-621249D01*
X342753Y-621879D01*
X342596Y-622719D01*
X342753Y-623559D01*
X343066Y-624189D01*
X343536Y-624609D01*
X344084Y-624819D01*
X344633Y-624714D01*
X345103Y-624399D01*
X345416Y-623979D01*
G01X349209Y-626394D02*
X349758Y-626814D01*
X350384Y-626919D01*
X350933Y-626814D01*
X351403Y-626289D01*
X351716Y-625554D01*
Y-620619D01*
G01Y-621459D02*
X351403Y-621039D01*
X350933Y-620724D01*
X350384Y-620619D01*
X349758Y-620829D01*
X349366Y-621249D01*
X349053Y-621984D01*
X348896Y-622719D01*
X348974Y-623349D01*
X349288Y-624084D01*
X349758Y-624609D01*
X350384Y-624819D01*
X350854Y-624714D01*
X351403Y-624294D01*
X351716Y-623874D01*
G01X355431Y-621984D02*
X357938D01*
X357703Y-621249D01*
X357311Y-620829D01*
X356763Y-620619D01*
X356214Y-620724D01*
X355744Y-621039D01*
X355431Y-621774D01*
X355274Y-622404D01*
Y-623034D01*
X355431Y-623664D01*
X355823Y-624294D01*
X356293Y-624714D01*
X356841Y-624819D01*
X357389Y-624609D01*
X357938Y-623979D01*
G01X360556Y-624819D02*
Y-620619D01*
G01Y-621774D02*
X360791Y-621249D01*
X361183Y-620829D01*
X361731Y-620619D01*
X362279Y-620829D01*
X362671Y-621249D01*
X362906Y-621774D01*
Y-624819D01*
G01Y-621774D02*
X363141Y-621249D01*
X363533Y-620829D01*
X364081Y-620619D01*
X364629Y-620829D01*
X365021Y-621249D01*
X365256Y-621879D01*
Y-624819D01*
G01X368031Y-621984D02*
X370538D01*
X370303Y-621249D01*
X369911Y-620829D01*
X369363Y-620619D01*
X368814Y-620724D01*
X368344Y-621039D01*
X368031Y-621774D01*
X367874Y-622404D01*
Y-623034D01*
X368031Y-623664D01*
X368423Y-624294D01*
X368893Y-624714D01*
X369441Y-624819D01*
X369989Y-624609D01*
X370538Y-623979D01*
G01X374174Y-624819D02*
Y-620619D01*
G01Y-621669D02*
X374488Y-621144D01*
X374958Y-620724D01*
X375584Y-620619D01*
X376133Y-620724D01*
X376603Y-621144D01*
X376838Y-621879D01*
Y-624819D01*
G01X381806Y-618519D02*
Y-624819D01*
G01X380709Y-620619D02*
X382903D01*
G01X385756Y-626919D02*
X390456D01*
G01X395033Y-621459D02*
X395346Y-621144D01*
X395581Y-620619D01*
X395738Y-619884D01*
X395581Y-619254D01*
X395268Y-618834D01*
X394719Y-618519D01*
X392604D01*
Y-624819D01*
X395189D01*
X395738Y-624399D01*
X396051Y-623769D01*
X396208Y-623034D01*
X396051Y-622299D01*
X395581Y-621669D01*
X395033Y-621459D01*
X392604D01*
G01X398983Y-624819D02*
Y-618519D01*
X400549D01*
X401176Y-618834D01*
X401646Y-619254D01*
X402038Y-619884D01*
X402351Y-620619D01*
X402429Y-621669D01*
X402351Y-622719D01*
X402038Y-623454D01*
X401646Y-624084D01*
X401176Y-624504D01*
X400549Y-624819D01*
X398983D01*
G01X367693Y-679936D02*
Y-671936D01*
X366493Y-673536D01*
G01Y-679936D02*
X368893D01*
G01X373793Y-676603D02*
X374493Y-675669D01*
X375093Y-675136D01*
X375893Y-674869D01*
X376593Y-675136D01*
X377093Y-675669D01*
X377493Y-676469D01*
X377593Y-677403D01*
X377493Y-678203D01*
X377093Y-679003D01*
X376493Y-679669D01*
X375793Y-679936D01*
X374993Y-679669D01*
X374293Y-678870D01*
X373893Y-677669D01*
X373793Y-676336D01*
X373993Y-674603D01*
X374293Y-673669D01*
X374793Y-672736D01*
X375493Y-672069D01*
X376193Y-671936D01*
X376893Y-672203D01*
X377393Y-672869D01*
G01X383693Y-680203D02*
X383493Y-680069D01*
Y-679803D01*
X383693Y-679669D01*
X383893Y-679803D01*
Y-680069D01*
X383693Y-680203D01*
G01X389793Y-676603D02*
X390493Y-675669D01*
X391093Y-675136D01*
X391893Y-674869D01*
X392593Y-675136D01*
X393093Y-675669D01*
X393493Y-676469D01*
X393593Y-677403D01*
X393493Y-678203D01*
X393093Y-679003D01*
X392493Y-679669D01*
X391793Y-679936D01*
X390993Y-679669D01*
X390293Y-678870D01*
X389893Y-677669D01*
X389793Y-676336D01*
X389993Y-674603D01*
X390293Y-673669D01*
X390793Y-672736D01*
X391493Y-672069D01*
X392193Y-671936D01*
X392893Y-672203D01*
X393393Y-672869D01*
G01X412693Y-679936D02*
Y-671936D01*
X411493Y-673536D01*
G01Y-679936D02*
X413893D01*
G01X420493D02*
X420693Y-678203D01*
X420993Y-676736D01*
X421393Y-675403D01*
X421893Y-673936D01*
X422693Y-671936D01*
X418693D01*
G01X428693Y-680203D02*
X428493Y-680069D01*
Y-679803D01*
X428693Y-679669D01*
X428893Y-679803D01*
Y-680069D01*
X428693Y-680203D01*
G01X434793Y-673269D02*
X435393Y-672469D01*
X436093Y-672069D01*
X436893Y-671936D01*
X437893Y-672203D01*
X438593Y-672869D01*
X438793Y-673669D01*
X438693Y-674470D01*
X438293Y-675136D01*
X436293Y-676469D01*
X435393Y-677403D01*
X434793Y-678736D01*
X434593Y-679936D01*
X438793D01*
G01X432493Y-654936D02*
Y-646936D01*
X434493D01*
X435293Y-647336D01*
X435893Y-647869D01*
X436393Y-648669D01*
X436793Y-649603D01*
X436893Y-650936D01*
X436793Y-652269D01*
X436393Y-653203D01*
X435893Y-654003D01*
X435293Y-654536D01*
X434493Y-654936D01*
X432493D01*
G54D78*
X316659Y266511D03*
X311541D03*
X316659Y274089D03*
X314100D03*
X311541D03*
G54D69*
X163110Y364169D03*
G54D79*
X320000Y396000D03*
Y403000D03*
X327000Y396000D03*
Y403000D03*
M02*
